FILE_TYPE = MACRO_DRAWING;
SET COLOR_WIRE YELLOW;
SET COLOR_PROP ORANGE;
SET COLOR_DOT WHITE;
SET COLOR_ARC YELLOW;
SET COLOR_BODY GREEN;
SET COLOR_NOTE PURPLE;
SET PROP_DISPLAY VALUE;
SET PAGE_NUMBER P369;
FORCEADD UNIVERSAL_GND..1
(-8375 725);
FORCEPROP 3 LASTPIN (-8375 775) SIG_NAME GND\g
J 0
(-8365 785);
DISPLAY 0.659574 (-8365 785);
PAINT MONO (-8365 785);
DISPLAY INVISIBLE (-8365 785);
FORCEPROP 2 LAST CDS_LIB pure_quanta_power
J 0
(-8375 725);
DISPLAY INVISIBLE (-8375 725);
FORCEPROP 1 LAST HDL_POWER GND
J 1
(-8350 650);
DISPLAY 0.872340 (-8350 650);
PAINT GREEN (-8350 650);
DISPLAY INVISIBLE (-8350 650);
FORCEPROP 1 LAST PATH I1
J 0
(-8300 725);
DISPLAY 0.872340 (-8300 725);
PAINT AQUA (-8300 725);
DISPLAY INVISIBLE (-8300 725);
FORCEADD Q_RES..1
(-8100 2200);
FORCEPROP 1 LAST LOCATION R3679
J 0
(-8300 2200);
DISPLAY 0.638298 (-8300 2200);
FORCEPROP 0 LAST $SEC 1
J 0
(-8225 2250);
DISPLAY 0.680851 (-8225 2250);
PAINT MONO (-8225 2250);
DISPLAY INVISIBLE (-8225 2250);
FORCEPROP 0 LAST CDS_SEC 1
J 0
(-8225 2250);
DISPLAY 1.021277 (-8225 2250);
DISPLAY INVISIBLE (-8225 2250);
FORCEPROP 1 LASTPIN (-8200 2200) $PN 1
J 0
(-8188 2212);
DISPLAY 0.787234 (-8188 2212);
PAINT MONO (-8188 2212);
FORCEPROP 1 LASTPIN (-8000 2200) $PN 2
J 0
(-8038 2212);
DISPLAY 0.787234 (-8038 2212);
PAINT MONO (-8038 2212);
FORCEPROP 1 LAST VALUE 0
J 2
(-7950 2200);
DISPLAY 0.404255 (-7950 2200);
FORCEPROP 1 LAST TOLERANCE 5%
J 0
(-7925 2200);
DISPLAY 0.404255 (-7925 2200);
FORCEPROP 1 LAST MATERIAL EMPTY
J 0
(-7875 2200);
DISPLAY 0.404255 (-7875 2200);
FORCEPROP 0 LAST ROOM ADC_MAM_BOM2
J 0
(-8300 2300);
DISPLAY 0.680851 (-8300 2300);
PAINT RED (-8300 2300);
FORCEPROP 2 LAST CDS_LIB pure_quanta
J 0
(-8100 2200);
DISPLAY INVISIBLE (-8100 2200);
FORCEPROP 1 LAST WATTAGE 1/16W
J 2
(-8000 2125);
DISPLAY 0.319149 (-8000 2125);
DISPLAY INVISIBLE (-8000 2125);
FORCEPROP 1 LAST PACK_TYPE 0402LF
J 0
(-7850 2200);
DISPLAY 0.510638 (-7850 2200);
DISPLAY INVISIBLE (-7850 2200);
FORCEPROP 1 LAST PATH I10
J 0
(-8150 2350);
DISPLAY 0.978723 (-8150 2350);
PAINT WHITE (-8150 2350);
DISPLAY INVISIBLE (-8150 2350);
FORCEPROP 1 LAST PART_NUMBER CS00002JB13
J 0
(-8175 2150);
DISPLAY 0.319149 (-8175 2150);
DISPLAY INVISIBLE (-8175 2150);
FORCEADD OFFPAGE..2
(-7400 5825);
FORCEPROP 2 LAST $XR0 258 
J 0
(-7211 5825);
DISPLAY 0.638298 (-7211 5825);
PAINT MONO (-7211 5825);
FORCEPROP 2 LAST CDS_LIB standard
J 0
(-7400 5825);
DISPLAY INVISIBLE (-7400 5825);
FORCEPROP 1 LAST OFFPAGE TRUE
J 0
(-7075 5700);
DISPLAY 0.872340 (-7075 5700);
DISPLAY INVISIBLE (-7075 5700);
FORCEPROP 1 LAST COMMENT_BODY TRUE
J 0
(-7445 5730);
DISPLAY 0.872340 (-7445 5730);
PAINT GREEN (-7445 5730);
DISPLAY INVISIBLE (-7445 5730);
FORCEPROP 2 LAST PATH I100
J 0
(-7200 5875);
DISPLAY 0.680851 (-7200 5875);
DISPLAY INVISIBLE (-7200 5875);
FORCEADD OFFPAGE..2
(-7400 5975);
FORCEPROP 2 LAST $XR0 258 
J 0
(-7211 5975);
DISPLAY 0.638298 (-7211 5975);
PAINT MONO (-7211 5975);
FORCEPROP 2 LAST CDS_LIB standard
J 0
(-7400 5975);
DISPLAY INVISIBLE (-7400 5975);
FORCEPROP 1 LAST OFFPAGE TRUE
J 0
(-7075 5850);
DISPLAY 0.872340 (-7075 5850);
DISPLAY INVISIBLE (-7075 5850);
FORCEPROP 1 LAST COMMENT_BODY TRUE
J 0
(-7445 5880);
DISPLAY 0.872340 (-7445 5880);
PAINT GREEN (-7445 5880);
DISPLAY INVISIBLE (-7445 5880);
FORCEPROP 2 LAST PATH I101
J 0
(-7200 6025);
DISPLAY 0.680851 (-7200 6025);
DISPLAY INVISIBLE (-7200 6025);
FORCEADD OFFPAGE..1
(-6600 5025);
FORCEPROP 2 LAST $XR0 140 
J 0
(-6852 5025);
DISPLAY 0.638298 (-6852 5025);
PAINT MONO (-6852 5025);
FORCEPROP 2 LAST CDS_LIB standard
J 0
(-6600 5025);
DISPLAY INVISIBLE (-6600 5025);
FORCEPROP 1 LAST OFFPAGE TRUE
J 0
(-6275 4900);
DISPLAY 0.872340 (-6275 4900);
PAINT GREEN (-6275 4900);
DISPLAY INVISIBLE (-6275 4900);
FORCEPROP 1 LAST COMMENT_BODY TRUE
J 0
(-6475 4925);
DISPLAY 0.872340 (-6475 4925);
PAINT GREEN (-6475 4925);
DISPLAY INVISIBLE (-6475 4925);
FORCEPROP 2 LAST PATH I102
J 0
(-6850 5075);
DISPLAY 0.680851 (-6850 5075);
DISPLAY INVISIBLE (-6850 5075);
FORCEADD OFFPAGE..1
(-6575 5350);
FORCEPROP 2 LAST $XR0 135 
J 0
(-6857 5350);
DISPLAY 0.638298 (-6857 5350);
PAINT MONO (-6857 5350);
FORCEPROP 2 LAST CDS_LIB standard
J 0
(-6575 5350);
DISPLAY INVISIBLE (-6575 5350);
FORCEPROP 1 LAST OFFPAGE TRUE
J 0
(-6250 5225);
DISPLAY 0.872340 (-6250 5225);
PAINT GREEN (-6250 5225);
DISPLAY INVISIBLE (-6250 5225);
FORCEPROP 1 LAST COMMENT_BODY TRUE
J 0
(-6450 5250);
DISPLAY 0.872340 (-6450 5250);
PAINT GREEN (-6450 5250);
DISPLAY INVISIBLE (-6450 5250);
FORCEPROP 2 LAST PATH I103
J 0
(-6825 5400);
DISPLAY 0.680851 (-6825 5400);
DISPLAY INVISIBLE (-6825 5400);
FORCEADD OFFPAGE..1
(-6575 5500);
FORCEPROP 2 LAST $XR0 134 
J 0
(-6857 5500);
DISPLAY 0.638298 (-6857 5500);
PAINT MONO (-6857 5500);
FORCEPROP 2 LAST CDS_LIB standard
J 0
(-6575 5500);
DISPLAY INVISIBLE (-6575 5500);
FORCEPROP 1 LAST OFFPAGE TRUE
J 0
(-6250 5375);
DISPLAY 0.872340 (-6250 5375);
PAINT GREEN (-6250 5375);
DISPLAY INVISIBLE (-6250 5375);
FORCEPROP 1 LAST COMMENT_BODY TRUE
J 0
(-6450 5400);
DISPLAY 0.872340 (-6450 5400);
PAINT GREEN (-6450 5400);
DISPLAY INVISIBLE (-6450 5400);
FORCEPROP 2 LAST PATH I104
J 0
(-6825 5550);
DISPLAY 0.680851 (-6825 5550);
DISPLAY INVISIBLE (-6825 5550);
FORCEADD OFFPAGE..1
(-6575 5850);
FORCEPROP 2 LAST $XR0 135 
J 0
(-6857 5850);
DISPLAY 0.638298 (-6857 5850);
PAINT MONO (-6857 5850);
FORCEPROP 2 LAST CDS_LIB standard
J 0
(-6575 5850);
DISPLAY INVISIBLE (-6575 5850);
FORCEPROP 1 LAST OFFPAGE TRUE
J 0
(-6250 5725);
DISPLAY 0.872340 (-6250 5725);
PAINT GREEN (-6250 5725);
DISPLAY INVISIBLE (-6250 5725);
FORCEPROP 1 LAST COMMENT_BODY TRUE
J 0
(-6450 5750);
DISPLAY 0.872340 (-6450 5750);
PAINT GREEN (-6450 5750);
DISPLAY INVISIBLE (-6450 5750);
FORCEPROP 2 LAST PATH I105
J 0
(-6825 5900);
DISPLAY 0.680851 (-6825 5900);
DISPLAY INVISIBLE (-6825 5900);
FORCEADD OFFPAGE..1
(-6575 6000);
FORCEPROP 2 LAST $XR0 134 
J 0
(-6857 6000);
DISPLAY 0.638298 (-6857 6000);
PAINT MONO (-6857 6000);
FORCEPROP 2 LAST CDS_LIB standard
J 0
(-6575 6000);
DISPLAY INVISIBLE (-6575 6000);
FORCEPROP 1 LAST OFFPAGE TRUE
J 0
(-6250 5875);
DISPLAY 0.872340 (-6250 5875);
PAINT GREEN (-6250 5875);
DISPLAY INVISIBLE (-6250 5875);
FORCEPROP 1 LAST COMMENT_BODY TRUE
J 0
(-6450 5900);
DISPLAY 0.872340 (-6450 5900);
PAINT GREEN (-6450 5900);
DISPLAY INVISIBLE (-6450 5900);
FORCEPROP 2 LAST PATH I106
J 0
(-6825 6050);
DISPLAY 0.680851 (-6825 6050);
DISPLAY INVISIBLE (-6825 6050);
FORCEADD Q_RES..1
(-5675 5025);
FORCEPROP 1 LAST LOCATION R3859
J 0
(-5850 5025);
DISPLAY 0.510638 (-5850 5025);
FORCEPROP 0 LAST $SEC 1
J 0
(-5800 5075);
DISPLAY 0.680851 (-5800 5075);
PAINT MONO (-5800 5075);
DISPLAY INVISIBLE (-5800 5075);
FORCEPROP 0 LAST CDS_SEC 1
J 0
(-5800 5075);
DISPLAY 1.021277 (-5800 5075);
DISPLAY INVISIBLE (-5800 5075);
FORCEPROP 1 LASTPIN (-5775 5025) $PN 1
J 0
(-5763 5037);
DISPLAY 0.787234 (-5763 5037);
PAINT MONO (-5763 5037);
FORCEPROP 1 LASTPIN (-5575 5025) $PN 2
J 0
(-5613 5037);
DISPLAY 0.787234 (-5613 5037);
PAINT MONO (-5613 5037);
FORCEPROP 1 LAST VALUE 0
J 2
(-5525 5025);
DISPLAY 0.404255 (-5525 5025);
FORCEPROP 1 LAST TOLERANCE 5%
J 0
(-5500 5025);
DISPLAY 0.404255 (-5500 5025);
FORCEPROP 1 LAST MATERIAL EMPTY
J 0
(-5450 5025);
DISPLAY 0.404255 (-5450 5025);
PAINT RED (-5450 5025);
FORCEPROP 2 LAST CDS_LIB pure_quanta
J 0
(-5675 5025);
DISPLAY INVISIBLE (-5675 5025);
FORCEPROP 1 LAST WATTAGE 1/16W
J 2
(-5575 4950);
DISPLAY 0.319149 (-5575 4950);
DISPLAY INVISIBLE (-5575 4950);
FORCEPROP 1 LAST PACK_TYPE 0402LF
J 0
(-5425 5025);
DISPLAY 0.510638 (-5425 5025);
DISPLAY INVISIBLE (-5425 5025);
FORCEPROP 1 LAST PATH I107
J 0
(-5725 5175);
DISPLAY 0.978723 (-5725 5175);
PAINT WHITE (-5725 5175);
DISPLAY INVISIBLE (-5725 5175);
FORCEPROP 1 LAST PART_NUMBER CS00002JB13
J 0
(-5750 4975);
DISPLAY 0.319149 (-5750 4975);
DISPLAY INVISIBLE (-5750 4975);
FORCEADD Q_RES..1
(-5650 5350);
FORCEPROP 1 LAST LOCATION R3866
J 0
(-5825 5350);
DISPLAY 0.510638 (-5825 5350);
FORCEPROP 0 LAST $SEC 1
J 0
(-5775 5400);
DISPLAY 0.680851 (-5775 5400);
PAINT MONO (-5775 5400);
DISPLAY INVISIBLE (-5775 5400);
FORCEPROP 0 LAST CDS_SEC 1
J 0
(-5775 5400);
DISPLAY 1.021277 (-5775 5400);
DISPLAY INVISIBLE (-5775 5400);
FORCEPROP 1 LASTPIN (-5750 5350) $PN 1
J 0
(-5738 5362);
DISPLAY 0.787234 (-5738 5362);
PAINT MONO (-5738 5362);
FORCEPROP 1 LASTPIN (-5550 5350) $PN 2
J 0
(-5588 5362);
DISPLAY 0.787234 (-5588 5362);
PAINT MONO (-5588 5362);
FORCEPROP 1 LAST TOLERANCE 5%
J 0
(-5475 5350);
DISPLAY 0.404255 (-5475 5350);
FORCEPROP 0 LAST ROOM ADC_TI_BOM3
J 0
(-5775 5300);
DISPLAY 0.553191 (-5775 5300);
PAINT RED (-5775 5300);
FORCEPROP 1 LAST VALUE 0
J 2
(-5500 5350);
DISPLAY 0.404255 (-5500 5350);
FORCEPROP 1 LAST MATERIAL EMPTY
J 0
(-5425 5350);
DISPLAY 0.404255 (-5425 5350);
PAINT RED (-5425 5350);
FORCEPROP 1 LAST PACK_TYPE 0402LF
J 0
(-5400 5350);
DISPLAY 0.510638 (-5400 5350);
DISPLAY INVISIBLE (-5400 5350);
FORCEPROP 1 LAST WATTAGE 1/16W
J 2
(-5550 5275);
DISPLAY 0.319149 (-5550 5275);
DISPLAY INVISIBLE (-5550 5275);
FORCEPROP 2 LAST CDS_LIB pure_quanta
J 0
(-5650 5350);
DISPLAY INVISIBLE (-5650 5350);
FORCEPROP 1 LAST PATH I108
J 0
(-5700 5500);
DISPLAY 0.978723 (-5700 5500);
PAINT WHITE (-5700 5500);
DISPLAY INVISIBLE (-5700 5500);
FORCEPROP 1 LAST PART_NUMBER CS00002JB13
J 0
(-5725 5300);
DISPLAY 0.319149 (-5725 5300);
DISPLAY INVISIBLE (-5725 5300);
FORCEADD Q_RES..1
(-5650 5500);
FORCEPROP 1 LAST LOCATION R3865
J 0
(-5825 5500);
DISPLAY 0.510638 (-5825 5500);
FORCEPROP 0 LAST $SEC 1
J 0
(-5775 5550);
DISPLAY 0.680851 (-5775 5550);
PAINT MONO (-5775 5550);
DISPLAY INVISIBLE (-5775 5550);
FORCEPROP 0 LAST CDS_SEC 1
J 0
(-5775 5550);
DISPLAY 1.021277 (-5775 5550);
DISPLAY INVISIBLE (-5775 5550);
FORCEPROP 1 LASTPIN (-5750 5500) $PN 1
J 0
(-5738 5512);
DISPLAY 0.787234 (-5738 5512);
PAINT MONO (-5738 5512);
FORCEPROP 1 LASTPIN (-5550 5500) $PN 2
J 0
(-5588 5512);
DISPLAY 0.787234 (-5588 5512);
PAINT MONO (-5588 5512);
FORCEPROP 1 LAST VALUE 0
J 2
(-5500 5500);
DISPLAY 0.404255 (-5500 5500);
FORCEPROP 0 LAST ROOM ADC_TI_BOM1
J 0
(-5750 5575);
DISPLAY 0.553191 (-5750 5575);
PAINT RED (-5750 5575);
FORCEPROP 1 LAST TOLERANCE 5%
J 0
(-5475 5500);
DISPLAY 0.404255 (-5475 5500);
FORCEPROP 1 LAST MATERIAL CHIP
J 0
(-5425 5500);
DISPLAY 0.404255 (-5425 5500);
FORCEPROP 1 LAST PACK_TYPE 0402LF
J 0
(-5400 5500);
DISPLAY 0.510638 (-5400 5500);
DISPLAY INVISIBLE (-5400 5500);
FORCEPROP 1 LAST WATTAGE 1/16W
J 2
(-5550 5425);
DISPLAY 0.319149 (-5550 5425);
DISPLAY INVISIBLE (-5550 5425);
FORCEPROP 2 LAST CDS_LIB pure_quanta
J 0
(-5650 5500);
DISPLAY INVISIBLE (-5650 5500);
FORCEPROP 1 LAST PATH I109
J 0
(-5700 5650);
DISPLAY 0.978723 (-5700 5650);
PAINT WHITE (-5700 5650);
DISPLAY INVISIBLE (-5700 5650);
FORCEPROP 1 LAST PART_NUMBER CS00002JB13
J 0
(-5725 5450);
DISPLAY 0.319149 (-5725 5450);
DISPLAY INVISIBLE (-5725 5450);
FORCEADD UNIVERSAL_GND..1
(-7925 2800);
FORCEPROP 3 LASTPIN (-7925 2850) SIG_NAME GND\g
J 0
(-7915 2860);
DISPLAY 0.659574 (-7915 2860);
PAINT MONO (-7915 2860);
DISPLAY INVISIBLE (-7915 2860);
FORCEPROP 2 LAST CDS_LIB pure_quanta_power
J 0
(-7925 2800);
DISPLAY INVISIBLE (-7925 2800);
FORCEPROP 1 LAST HDL_POWER GND
J 1
(-7900 2725);
DISPLAY 0.872340 (-7900 2725);
PAINT GREEN (-7900 2725);
DISPLAY INVISIBLE (-7900 2725);
FORCEPROP 1 LAST PATH I11
J 0
(-7850 2800);
DISPLAY 0.872340 (-7850 2800);
PAINT AQUA (-7850 2800);
DISPLAY INVISIBLE (-7850 2800);
FORCEADD Q_RES..1
(-5650 5850);
FORCEPROP 1 LAST LOCATION R3864
J 0
(-5825 5850);
DISPLAY 0.510638 (-5825 5850);
FORCEPROP 0 LAST $SEC 1
J 0
(-5775 5900);
DISPLAY 0.680851 (-5775 5900);
PAINT MONO (-5775 5900);
DISPLAY INVISIBLE (-5775 5900);
FORCEPROP 0 LAST CDS_SEC 1
J 0
(-5775 5900);
DISPLAY 1.021277 (-5775 5900);
DISPLAY INVISIBLE (-5775 5900);
FORCEPROP 1 LASTPIN (-5750 5850) $PN 1
J 0
(-5738 5862);
DISPLAY 0.787234 (-5738 5862);
PAINT MONO (-5738 5862);
FORCEPROP 1 LASTPIN (-5550 5850) $PN 2
J 0
(-5588 5862);
DISPLAY 0.787234 (-5588 5862);
PAINT MONO (-5588 5862);
FORCEPROP 0 LAST ROOM ADC_MAM_BOM2
J 0
(-5750 5800);
DISPLAY 0.553191 (-5750 5800);
PAINT RED (-5750 5800);
FORCEPROP 1 LAST MATERIAL EMPTY
J 0
(-5425 5850);
DISPLAY 0.404255 (-5425 5850);
PAINT RED (-5425 5850);
FORCEPROP 1 LAST VALUE 0
J 2
(-5500 5850);
DISPLAY 0.404255 (-5500 5850);
FORCEPROP 1 LAST TOLERANCE 5%
J 0
(-5475 5850);
DISPLAY 0.404255 (-5475 5850);
FORCEPROP 1 LAST PACK_TYPE 0402LF
J 0
(-5400 5850);
DISPLAY 0.510638 (-5400 5850);
DISPLAY INVISIBLE (-5400 5850);
FORCEPROP 1 LAST WATTAGE 1/16W
J 2
(-5550 5775);
DISPLAY 0.319149 (-5550 5775);
DISPLAY INVISIBLE (-5550 5775);
FORCEPROP 2 LAST CDS_LIB pure_quanta
J 0
(-5650 5850);
DISPLAY INVISIBLE (-5650 5850);
FORCEPROP 1 LAST PATH I110
J 0
(-5700 6000);
DISPLAY 0.978723 (-5700 6000);
PAINT WHITE (-5700 6000);
DISPLAY INVISIBLE (-5700 6000);
FORCEPROP 1 LAST PART_NUMBER CS00002JB13
J 0
(-5725 5800);
DISPLAY 0.319149 (-5725 5800);
DISPLAY INVISIBLE (-5725 5800);
FORCEADD UNIVERSAL_GND..1
(-4950 5150);
FORCEPROP 3 LASTPIN (-4950 5200) SIG_NAME GND\g
J 0
(-4940 5210);
DISPLAY 0.659574 (-4940 5210);
PAINT MONO (-4940 5210);
DISPLAY INVISIBLE (-4940 5210);
FORCEPROP 2 LAST CDS_LIB pure_quanta_power
J 0
(-4950 5150);
DISPLAY INVISIBLE (-4950 5150);
FORCEPROP 1 LAST HDL_POWER GND
J 1
(-4925 5075);
DISPLAY 0.872340 (-4925 5075);
PAINT GREEN (-4925 5075);
DISPLAY INVISIBLE (-4925 5075);
FORCEPROP 1 LAST PATH I111
J 0
(-4875 5150);
DISPLAY 0.872340 (-4875 5150);
PAINT AQUA (-4875 5150);
DISPLAY INVISIBLE (-4875 5150);
FORCEADD Q_CAP..1
R 2
(-4950 5325);
FORCEPROP 1 LAST LOCATION C37
J 2
(-4750 5450);
DISPLAY 0.787234 (-4750 5450);
FORCEPROP 0 LAST $SEC 1
J 0
(-5000 5475);
DISPLAY 0.680851 (-5000 5475);
PAINT MONO (-5000 5475);
DISPLAY INVISIBLE (-5000 5475);
FORCEPROP 0 LAST CDS_SEC 1
J 0
(-5000 5475);
DISPLAY 1.021277 (-5000 5475);
DISPLAY INVISIBLE (-5000 5475);
FORCEPROP 1 LASTPIN (-4950 5425) $PN 1
J 2
(-4960 5405);
DISPLAY 0.787234 (-4960 5405);
PAINT MONO (-4960 5405);
FORCEPROP 1 LASTPIN (-4950 5225) $PN 2
J 2
(-4960 5205);
DISPLAY 0.787234 (-4960 5205);
PAINT MONO (-4960 5205);
FORCEPROP 1 LAST VOLTAGE 25V
J 2
(-4800 5350);
DISPLAY 0.510638 (-4800 5350);
FORCEPROP 1 LAST TOLERANCE 10%
J 2
(-4800 5300);
DISPLAY 0.510638 (-4800 5300);
FORCEPROP 1 LAST VALUE 0.1UF
J 2
(-4775 5400);
DISPLAY 0.510638 (-4775 5400);
FORCEPROP 1 LAST PACK_TYPE 0402
J 2
(-4775 5150);
DISPLAY 0.510638 (-4775 5150);
FORCEPROP 1 LAST MATERIAL X7R
J 2
(-4800 5250);
DISPLAY 0.510638 (-4800 5250);
PAINT RED (-4800 5250);
FORCEPROP 0 LAST ROOM ADC_TI_BOM1
J 0
(-4875 5125);
DISPLAY 0.553191 (-4875 5125);
PAINT RED (-4875 5125);
FORCEPROP 2 LAST CDS_LIB pure_quanta
J 0
(-4950 5325);
DISPLAY INVISIBLE (-4950 5325);
FORCEPROP 1 LAST PATH I112
J 2
(-5000 5475);
DISPLAY 0.978723 (-5000 5475);
PAINT WHITE (-5000 5475);
DISPLAY INVISIBLE (-5000 5475);
FORCEPROP 1 LAST PART_NUMBER CH4104K1B00
J 2
(-4650 5200);
DISPLAY 0.510638 (-4650 5200);
DISPLAY INVISIBLE (-4650 5200);
FORCEADD UNIVERSAL_GND..1
(-4925 5650);
FORCEPROP 3 LASTPIN (-4925 5700) SIG_NAME GND\g
J 0
(-4915 5710);
DISPLAY 0.659574 (-4915 5710);
PAINT MONO (-4915 5710);
DISPLAY INVISIBLE (-4915 5710);
FORCEPROP 2 LAST CDS_LIB pure_quanta_power
J 0
(-4925 5650);
DISPLAY INVISIBLE (-4925 5650);
FORCEPROP 1 LAST HDL_POWER GND
J 1
(-4900 5575);
DISPLAY 0.872340 (-4900 5575);
PAINT GREEN (-4900 5575);
DISPLAY INVISIBLE (-4900 5575);
FORCEPROP 1 LAST PATH I113
J 0
(-4850 5650);
DISPLAY 0.872340 (-4850 5650);
PAINT AQUA (-4850 5650);
DISPLAY INVISIBLE (-4850 5650);
FORCEADD Q_CAP..1
(-4925 5850);
FORCEPROP 1 LAST LOCATION C2176
J 0
(-4875 5950);
DISPLAY 0.510638 (-4875 5950);
FORCEPROP 2 LAST $SEC 1
J 0
(-4875 6050);
DISPLAY 0.680851 (-4875 6050);
PAINT MONO (-4875 6050);
DISPLAY INVISIBLE (-4875 6050);
FORCEPROP 0 LAST CDS_SEC 1
J 0
(-4875 6025);
DISPLAY 1.021277 (-4875 6025);
DISPLAY INVISIBLE (-4875 6025);
FORCEPROP 1 LASTPIN (-4925 5950) $PN 1
J 0
(-4915 5930);
DISPLAY 0.787234 (-4915 5930);
PAINT MONO (-4915 5930);
FORCEPROP 1 LASTPIN (-4925 5750) $PN 2
J 0
(-4915 5730);
DISPLAY 0.787234 (-4915 5730);
PAINT MONO (-4915 5730);
FORCEPROP 1 LAST MATERIAL EMPTY
J 0
(-4875 5750);
DISPLAY 0.510638 (-4875 5750);
FORCEPROP 1 LAST TOLERANCE 5%
J 0
(-4875 5800);
DISPLAY 0.510638 (-4875 5800);
FORCEPROP 1 LAST VALUE 100PF
J 0
(-4875 5900);
DISPLAY 0.510638 (-4875 5900);
FORCEPROP 0 LAST ROOM ADC_MAM_BOM2
J 0
(-4875 5625);
DISPLAY 0.553191 (-4875 5625);
PAINT RED (-4875 5625);
FORCEPROP 1 LAST PACK_TYPE 0402
J 0
(-4875 5650);
DISPLAY 0.510638 (-4875 5650);
FORCEPROP 1 LAST VOLTAGE 50V
J 0
(-4875 5850);
DISPLAY 0.510638 (-4875 5850);
FORCEPROP 2 LAST CDS_LIB pure_quanta
J 0
(-4925 5850);
DISPLAY INVISIBLE (-4925 5850);
FORCEPROP 1 LAST PATH I114
J 0
(-4875 6000);
DISPLAY 0.978723 (-4875 6000);
PAINT WHITE (-4875 6000);
DISPLAY INVISIBLE (-4875 6000);
FORCEPROP 1 LAST PART_NUMBER CH11006JB18
J 0
(-4875 5700);
DISPLAY 0.510638 (-4875 5700);
DISPLAY INVISIBLE (-4875 5700);
FORCEADD Q_RES..1
(-5650 6000);
FORCEPROP 1 LAST LOCATION R3863
J 0
(-5825 6000);
DISPLAY 0.510638 (-5825 6000);
FORCEPROP 0 LAST $SEC 1
J 0
(-5775 6050);
DISPLAY 0.680851 (-5775 6050);
PAINT MONO (-5775 6050);
DISPLAY INVISIBLE (-5775 6050);
FORCEPROP 0 LAST CDS_SEC 1
J 0
(-5775 6050);
DISPLAY 1.021277 (-5775 6050);
DISPLAY INVISIBLE (-5775 6050);
FORCEPROP 1 LASTPIN (-5750 6000) $PN 1
J 0
(-5738 6012);
DISPLAY 0.787234 (-5738 6012);
PAINT MONO (-5738 6012);
FORCEPROP 1 LASTPIN (-5550 6000) $PN 2
J 0
(-5588 6012);
DISPLAY 0.787234 (-5588 6012);
PAINT MONO (-5588 6012);
FORCEPROP 1 LAST MATERIAL EMPTY
J 0
(-5425 6000);
DISPLAY 0.404255 (-5425 6000);
PAINT RED (-5425 6000);
FORCEPROP 1 LAST TOLERANCE 5%
J 0
(-5475 6000);
DISPLAY 0.404255 (-5475 6000);
FORCEPROP 1 LAST VALUE 0
J 2
(-5500 6000);
DISPLAY 0.404255 (-5500 6000);
FORCEPROP 2 LAST CDS_LIB pure_quanta
J 0
(-5650 6000);
DISPLAY INVISIBLE (-5650 6000);
FORCEPROP 1 LAST WATTAGE 1/16W
J 2
(-5550 5925);
DISPLAY 0.319149 (-5550 5925);
DISPLAY INVISIBLE (-5550 5925);
FORCEPROP 1 LAST PACK_TYPE 0402LF
J 0
(-5400 6000);
DISPLAY 0.510638 (-5400 6000);
DISPLAY INVISIBLE (-5400 6000);
FORCEPROP 1 LAST PATH I115
J 0
(-5700 6150);
DISPLAY 0.978723 (-5700 6150);
PAINT WHITE (-5700 6150);
DISPLAY INVISIBLE (-5700 6150);
FORCEPROP 1 LAST PART_NUMBER CS00002JB13
J 0
(-5725 5950);
DISPLAY 0.319149 (-5725 5950);
DISPLAY INVISIBLE (-5725 5950);
FORCEADD OFFPAGE..2
(-4700 5025);
FORCEPROP 2 LAST $XR0 258 
J 0
(-4511 5025);
DISPLAY 0.638298 (-4511 5025);
PAINT MONO (-4511 5025);
FORCEPROP 2 LAST CDS_LIB standard
J 0
(-4700 5025);
DISPLAY INVISIBLE (-4700 5025);
FORCEPROP 1 LAST OFFPAGE TRUE
J 0
(-4375 4900);
DISPLAY 0.872340 (-4375 4900);
DISPLAY INVISIBLE (-4375 4900);
FORCEPROP 1 LAST COMMENT_BODY TRUE
J 0
(-4745 4930);
DISPLAY 0.872340 (-4745 4930);
PAINT GREEN (-4745 4930);
DISPLAY INVISIBLE (-4745 4930);
FORCEPROP 2 LAST PATH I116
J 0
(-4500 5075);
DISPLAY 0.680851 (-4500 5075);
DISPLAY INVISIBLE (-4500 5075);
FORCEADD OFFPAGE..2
(-4675 5500);
FORCEPROP 2 LAST $XR0 258 
J 0
(-4486 5500);
DISPLAY 0.638298 (-4486 5500);
PAINT MONO (-4486 5500);
FORCEPROP 2 LAST CDS_LIB standard
J 0
(-4675 5500);
DISPLAY INVISIBLE (-4675 5500);
FORCEPROP 1 LAST OFFPAGE TRUE
J 0
(-4350 5375);
DISPLAY 0.872340 (-4350 5375);
DISPLAY INVISIBLE (-4350 5375);
FORCEPROP 1 LAST COMMENT_BODY TRUE
J 0
(-4720 5405);
DISPLAY 0.872340 (-4720 5405);
PAINT GREEN (-4720 5405);
DISPLAY INVISIBLE (-4720 5405);
FORCEPROP 2 LAST PATH I117
J 0
(-4475 5550);
DISPLAY 0.680851 (-4475 5550);
DISPLAY INVISIBLE (-4475 5550);
FORCEADD UNIVERSAL_GND..1
(-4200 5150);
FORCEPROP 3 LASTPIN (-4200 5200) SIG_NAME GND\g
J 0
(-4190 5210);
DISPLAY 0.659574 (-4190 5210);
PAINT MONO (-4190 5210);
DISPLAY INVISIBLE (-4190 5210);
FORCEPROP 2 LAST CDS_LIB pure_quanta_power
J 0
(-4200 5150);
DISPLAY INVISIBLE (-4200 5150);
FORCEPROP 1 LAST HDL_POWER GND
J 1
(-4175 5075);
DISPLAY 0.872340 (-4175 5075);
PAINT GREEN (-4175 5075);
DISPLAY INVISIBLE (-4175 5075);
FORCEPROP 1 LAST PATH I118
J 0
(-4125 5150);
DISPLAY 0.872340 (-4125 5150);
PAINT AQUA (-4125 5150);
DISPLAY INVISIBLE (-4125 5150);
FORCEADD Q_CAP..1
R 2
(-4200 5350);
FORCEPROP 1 LAST LOCATION C1347
J 2
(-4025 5475);
DISPLAY 0.638298 (-4025 5475);
FORCEPROP 0 LAST $SEC 1
J 0
(-4250 5500);
DISPLAY 0.680851 (-4250 5500);
PAINT MONO (-4250 5500);
DISPLAY INVISIBLE (-4250 5500);
FORCEPROP 0 LAST CDS_SEC 1
J 0
(-4250 5500);
DISPLAY 1.021277 (-4250 5500);
DISPLAY INVISIBLE (-4250 5500);
FORCEPROP 1 LASTPIN (-4200 5450) $PN 1
J 2
(-4210 5430);
DISPLAY 0.787234 (-4210 5430);
PAINT MONO (-4210 5430);
FORCEPROP 1 LASTPIN (-4200 5250) $PN 2
J 2
(-4210 5230);
DISPLAY 0.787234 (-4210 5230);
PAINT MONO (-4210 5230);
FORCEPROP 1 LAST VALUE 0.1UF
J 2
(-4025 5425);
DISPLAY 0.510638 (-4025 5425);
FORCEPROP 1 LAST VOLTAGE 25V
J 2
(-4050 5375);
DISPLAY 0.510638 (-4050 5375);
FORCEPROP 1 LAST TOLERANCE 10%
J 2
(-4050 5325);
DISPLAY 0.510638 (-4050 5325);
FORCEPROP 1 LAST PACK_TYPE 0402
J 2
(-4025 5175);
DISPLAY 0.510638 (-4025 5175);
FORCEPROP 1 LAST MATERIAL X7R
J 2
(-4050 5275);
DISPLAY 0.510638 (-4050 5275);
FORCEPROP 2 LAST CDS_LIB pure_quanta
J 0
(-4200 5350);
DISPLAY INVISIBLE (-4200 5350);
FORCEPROP 1 LAST PATH I119
J 2
(-4250 5500);
DISPLAY 0.978723 (-4250 5500);
PAINT WHITE (-4250 5500);
DISPLAY INVISIBLE (-4250 5500);
FORCEPROP 1 LAST PART_NUMBER CH4104K1B00
J 2
(-3900 5225);
DISPLAY 0.510638 (-3900 5225);
DISPLAY INVISIBLE (-3900 5225);
FORCEADD UNIVERSAL_GND..1
(-8900 4175);
FORCEPROP 3 LASTPIN (-8900 4225) SIG_NAME GND\g
J 0
(-8890 4235);
DISPLAY 0.659574 (-8890 4235);
PAINT MONO (-8890 4235);
DISPLAY INVISIBLE (-8890 4235);
FORCEPROP 2 LAST CDS_LIB pure_quanta_power
J 0
(-8900 4175);
DISPLAY INVISIBLE (-8900 4175);
FORCEPROP 1 LAST HDL_POWER GND
J 1
(-8875 4100);
DISPLAY 0.872340 (-8875 4100);
PAINT GREEN (-8875 4100);
DISPLAY INVISIBLE (-8875 4100);
FORCEPROP 1 LAST PATH I12
J 0
(-8825 4175);
DISPLAY 0.872340 (-8825 4175);
PAINT AQUA (-8825 4175);
DISPLAY INVISIBLE (-8825 4175);
FORCEADD UNIVERSAL_GND..1
(-3825 5150);
FORCEPROP 3 LASTPIN (-3825 5200) SIG_NAME GND\g
J 0
(-3815 5210);
DISPLAY 0.659574 (-3815 5210);
PAINT MONO (-3815 5210);
DISPLAY INVISIBLE (-3815 5210);
FORCEPROP 2 LAST CDS_LIB pure_quanta_power
J 0
(-3825 5150);
DISPLAY INVISIBLE (-3825 5150);
FORCEPROP 1 LAST HDL_POWER GND
J 1
(-3800 5075);
DISPLAY 0.872340 (-3800 5075);
PAINT GREEN (-3800 5075);
DISPLAY INVISIBLE (-3800 5075);
FORCEPROP 1 LAST PATH I120
J 0
(-3750 5150);
DISPLAY 0.872340 (-3750 5150);
PAINT AQUA (-3750 5150);
DISPLAY INVISIBLE (-3750 5150);
FORCEADD Q_CAP..1
(-3825 5350);
FORCEPROP 1 LAST LOCATION C1767
J 0
(-3775 5450);
DISPLAY 0.510638 (-3775 5450);
FORCEPROP 2 LAST $SEC 1
J 0
(-3775 5550);
DISPLAY 0.680851 (-3775 5550);
PAINT MONO (-3775 5550);
DISPLAY INVISIBLE (-3775 5550);
FORCEPROP 2 LAST CDS_SEC 1
J 0
(-3775 5550);
DISPLAY 1.021277 (-3775 5550);
DISPLAY INVISIBLE (-3775 5550);
FORCEPROP 1 LASTPIN (-3825 5450) $PN 1
J 0
(-3815 5430);
DISPLAY 0.787234 (-3815 5430);
FORCEPROP 1 LASTPIN (-3825 5250) $PN 2
J 0
(-3815 5230);
DISPLAY 0.787234 (-3815 5230);
FORCEPROP 1 LAST PACK_TYPE C0805
J 0
(-3775 5150);
DISPLAY 0.510638 (-3775 5150);
FORCEPROP 1 LAST VOLTAGE 16V
J 0
(-3775 5350);
DISPLAY 0.510638 (-3775 5350);
FORCEPROP 1 LAST TOLERANCE 10%
J 0
(-3775 5300);
DISPLAY 0.510638 (-3775 5300);
FORCEPROP 1 LAST VALUE 10UF
J 0
(-3775 5400);
DISPLAY 0.510638 (-3775 5400);
FORCEPROP 1 LAST MATERIAL X6S
J 0
(-3775 5250);
DISPLAY 0.510638 (-3775 5250);
FORCEPROP 2 LAST CDS_LIB pure_quanta
J 0
(-3825 5350);
PAINT MONO (-3825 5350);
DISPLAY INVISIBLE (-3825 5350);
FORCEPROP 1 LAST PATH I121
J 0
(-3775 5500);
DISPLAY 0.978723 (-3775 5500);
PAINT WHITE (-3775 5500);
DISPLAY INVISIBLE (-3775 5500);
FORCEPROP 1 LAST PART_NUMBER CH6103KEA00
J 0
(-3775 5200);
DISPLAY 0.510638 (-3775 5200);
DISPLAY INVISIBLE (-3775 5200);
FORCEADD OFFPAGE..2
(-4675 6000);
FORCEPROP 2 LAST $XR0 258 
J 0
(-4486 6000);
DISPLAY 0.638298 (-4486 6000);
PAINT MONO (-4486 6000);
FORCEPROP 2 LAST CDS_LIB standard
J 0
(-4675 6000);
DISPLAY INVISIBLE (-4675 6000);
FORCEPROP 1 LAST OFFPAGE TRUE
J 0
(-4350 5875);
DISPLAY 0.872340 (-4350 5875);
DISPLAY INVISIBLE (-4350 5875);
FORCEPROP 1 LAST COMMENT_BODY TRUE
J 0
(-4720 5905);
DISPLAY 0.872340 (-4720 5905);
PAINT GREEN (-4720 5905);
DISPLAY INVISIBLE (-4720 5905);
FORCEPROP 2 LAST PATH I122
J 0
(-4475 6050);
DISPLAY 0.680851 (-4475 6050);
DISPLAY INVISIBLE (-4475 6050);
FORCEADD OFFPAGE..2
(-3425 975);
FORCEPROP 2 LAST $XR0 258 
J 0
(-3236 975);
DISPLAY 0.638298 (-3236 975);
PAINT MONO (-3236 975);
FORCEPROP 2 LAST CDS_LIB standard
J 0
(-3425 975);
DISPLAY INVISIBLE (-3425 975);
FORCEPROP 1 LAST OFFPAGE TRUE
J 0
(-3100 850);
DISPLAY 0.872340 (-3100 850);
DISPLAY INVISIBLE (-3100 850);
FORCEPROP 1 LAST COMMENT_BODY TRUE
J 0
(-3470 880);
DISPLAY 0.872340 (-3470 880);
PAINT GREEN (-3470 880);
DISPLAY INVISIBLE (-3470 880);
FORCEPROP 2 LAST PATH I123
J 0
(-3225 1025);
DISPLAY 0.680851 (-3225 1025);
DISPLAY INVISIBLE (-3225 1025);
FORCEADD OFFPAGE..2
(-3425 1075);
FORCEPROP 2 LAST $XR0 258 
J 0
(-3236 1075);
DISPLAY 0.638298 (-3236 1075);
PAINT MONO (-3236 1075);
FORCEPROP 2 LAST CDS_LIB standard
J 0
(-3425 1075);
DISPLAY INVISIBLE (-3425 1075);
FORCEPROP 1 LAST OFFPAGE TRUE
J 0
(-3100 950);
DISPLAY 0.872340 (-3100 950);
DISPLAY INVISIBLE (-3100 950);
FORCEPROP 1 LAST COMMENT_BODY TRUE
J 0
(-3470 980);
DISPLAY 0.872340 (-3470 980);
PAINT GREEN (-3470 980);
DISPLAY INVISIBLE (-3470 980);
FORCEPROP 2 LAST PATH I124
J 0
(-3225 1125);
DISPLAY 0.680851 (-3225 1125);
DISPLAY INVISIBLE (-3225 1125);
FORCEADD UNIVERSAL_GND..1
(-3475 1675);
FORCEPROP 3 LASTPIN (-3475 1725) SIG_NAME GND\g
J 0
(-3465 1735);
DISPLAY 0.659574 (-3465 1735);
PAINT MONO (-3465 1735);
DISPLAY INVISIBLE (-3465 1735);
FORCEPROP 2 LAST CDS_LIB pure_quanta_power
J 0
(-3475 1675);
DISPLAY INVISIBLE (-3475 1675);
FORCEPROP 1 LAST HDL_POWER GND
J 1
(-3450 1600);
DISPLAY 0.872340 (-3450 1600);
PAINT GREEN (-3450 1600);
DISPLAY INVISIBLE (-3450 1600);
FORCEPROP 1 LAST PATH I125
J 0
(-3400 1675);
DISPLAY 0.872340 (-3400 1675);
PAINT AQUA (-3400 1675);
DISPLAY INVISIBLE (-3400 1675);
FORCEADD OFFPAGE..4
R 2
(-2750 1725);
FORCEPROP 2 LAST $XR0 258 
J 0
(-3032 1725);
DISPLAY 0.638298 (-3032 1725);
PAINT MONO (-3032 1725);
FORCEPROP 2 LAST CDS_LIB standard
J 2
(-2750 1725);
DISPLAY INVISIBLE (-2750 1725);
FORCEPROP 1 LAST OFFPAGE TRUE
J 2
(-3075 1600);
DISPLAY 0.872340 (-3075 1600);
DISPLAY INVISIBLE (-3075 1600);
FORCEPROP 1 LAST COMMENT_BODY TRUE
J 2
(-2725 1625);
DISPLAY 0.872340 (-2725 1625);
PAINT GREEN (-2725 1625);
DISPLAY INVISIBLE (-2725 1625);
FORCEPROP 2 LAST PATH I126
J 0
(-3000 1775);
DISPLAY 0.680851 (-3000 1775);
DISPLAY INVISIBLE (-3000 1775);
FORCEADD OFFPAGE..4
R 2
(-2750 1775);
FORCEPROP 2 LAST $XR0 258 
J 0
(-3032 1775);
DISPLAY 0.638298 (-3032 1775);
PAINT MONO (-3032 1775);
FORCEPROP 2 LAST CDS_LIB standard
J 2
(-2750 1775);
DISPLAY INVISIBLE (-2750 1775);
FORCEPROP 1 LAST OFFPAGE TRUE
J 2
(-3075 1650);
DISPLAY 0.872340 (-3075 1650);
DISPLAY INVISIBLE (-3075 1650);
FORCEPROP 1 LAST COMMENT_BODY TRUE
J 2
(-2725 1675);
DISPLAY 0.872340 (-2725 1675);
PAINT GREEN (-2725 1675);
DISPLAY INVISIBLE (-2725 1675);
FORCEPROP 2 LAST PATH I127
J 0
(-3000 1825);
DISPLAY 0.680851 (-3000 1825);
DISPLAY INVISIBLE (-3000 1825);
FORCEADD OFFPAGE..4
R 2
(-2750 1675);
FORCEPROP 2 LAST $XR0 258 
J 0
(-3032 1675);
DISPLAY 0.638298 (-3032 1675);
PAINT MONO (-3032 1675);
FORCEPROP 2 LAST CDS_LIB standard
J 2
(-2750 1675);
DISPLAY INVISIBLE (-2750 1675);
FORCEPROP 1 LAST OFFPAGE TRUE
J 2
(-3075 1550);
DISPLAY 0.872340 (-3075 1550);
DISPLAY INVISIBLE (-3075 1550);
FORCEPROP 1 LAST COMMENT_BODY TRUE
J 2
(-2725 1575);
DISPLAY 0.872340 (-2725 1575);
PAINT GREEN (-2725 1575);
DISPLAY INVISIBLE (-2725 1575);
FORCEPROP 2 LAST PATH I128
J 0
(-3000 1725);
DISPLAY 0.680851 (-3000 1725);
DISPLAY INVISIBLE (-3000 1725);
FORCEADD OFFPAGE..4
R 2
(-2750 1825);
FORCEPROP 2 LAST $XR0 258 
J 0
(-3032 1825);
DISPLAY 0.638298 (-3032 1825);
PAINT MONO (-3032 1825);
FORCEPROP 2 LAST CDS_LIB standard
J 2
(-2750 1825);
DISPLAY INVISIBLE (-2750 1825);
FORCEPROP 1 LAST OFFPAGE TRUE
J 2
(-3075 1700);
DISPLAY 0.872340 (-3075 1700);
DISPLAY INVISIBLE (-3075 1700);
FORCEPROP 1 LAST COMMENT_BODY TRUE
J 2
(-2725 1725);
DISPLAY 0.872340 (-2725 1725);
PAINT GREEN (-2725 1725);
DISPLAY INVISIBLE (-2725 1725);
FORCEPROP 2 LAST PATH I129
J 0
(-3000 1875);
DISPLAY 0.680851 (-3000 1875);
DISPLAY INVISIBLE (-3000 1875);
FORCEADD UNIVERSAL_GND..1
(-8900 2900);
FORCEPROP 3 LASTPIN (-8900 2950) SIG_NAME GND\g
J 0
(-8890 2960);
DISPLAY 0.659574 (-8890 2960);
PAINT MONO (-8890 2960);
DISPLAY INVISIBLE (-8890 2960);
FORCEPROP 2 LAST CDS_LIB pure_quanta_power
J 0
(-8900 2900);
DISPLAY INVISIBLE (-8900 2900);
FORCEPROP 1 LAST HDL_POWER GND
J 1
(-8875 2825);
DISPLAY 0.872340 (-8875 2825);
PAINT GREEN (-8875 2825);
DISPLAY INVISIBLE (-8875 2825);
FORCEPROP 1 LAST PATH I13
J 0
(-8825 2900);
DISPLAY 0.872340 (-8825 2900);
PAINT AQUA (-8825 2900);
DISPLAY INVISIBLE (-8825 2900);
FORCEADD Q_RES..2
(-3475 2000);
FORCEPROP 1 LAST LOCATION R3690
J 0
(-3430 2125);
DISPLAY 0.808511 (-3430 2125);
FORCEPROP 0 LAST $SEC 1
J 0
(-3425 2175);
DISPLAY 0.680851 (-3425 2175);
PAINT MONO (-3425 2175);
DISPLAY INVISIBLE (-3425 2175);
FORCEPROP 0 LAST CDS_SEC 1
J 0
(-3425 2175);
DISPLAY 1.021277 (-3425 2175);
DISPLAY INVISIBLE (-3425 2175);
FORCEPROP 1 LASTPIN (-3475 2100) $PN 1
J 0
(-3470 2062);
DISPLAY 0.787234 (-3470 2062);
PAINT MONO (-3470 2062);
FORCEPROP 1 LASTPIN (-3475 1900) $PN 2
J 0
(-3470 1910);
DISPLAY 0.787234 (-3470 1910);
PAINT MONO (-3470 1910);
FORCEPROP 1 LAST PACK_TYPE 0402LF
J 0
(-3435 1825);
DISPLAY 0.638298 (-3435 1825);
FORCEPROP 1 LAST WATTAGE 1/16W
J 0
(-3435 1975);
DISPLAY 0.638298 (-3435 1975);
FORCEPROP 1 LAST TOLERANCE 1%
J 0
(-3430 2025);
DISPLAY 0.638298 (-3430 2025);
FORCEPROP 1 LAST MATERIAL EMPTY
J 0
(-3435 1925);
DISPLAY 0.638298 (-3435 1925);
PAINT RED (-3435 1925);
FORCEPROP 1 LAST VALUE 4.7K
J 0
(-3430 2075);
DISPLAY 0.638298 (-3430 2075);
FORCEPROP 0 LAST ROOM ADC_TI_BOM1
J 0
(-3425 2200);
DISPLAY 0.680851 (-3425 2200);
PAINT RED (-3425 2200);
FORCEPROP 2 LAST CDS_LIB pure_quanta
J 0
(-3475 2000);
DISPLAY INVISIBLE (-3475 2000);
FORCEPROP 1 LAST PATH I130
J 0
(-3425 2175);
DISPLAY 0.978723 (-3425 2175);
PAINT WHITE (-3425 2175);
DISPLAY INVISIBLE (-3425 2175);
FORCEPROP 1 LAST PART_NUMBER CS24702FB06
J 0
(-3435 1875);
DISPLAY 0.638298 (-3435 1875);
DISPLAY INVISIBLE (-3435 1875);
FORCEADD Q_RES..2
(-3475 2500);
FORCEPROP 1 LAST LOCATION R3689
J 0
(-3425 2600);
DISPLAY 0.638298 (-3425 2600);
FORCEPROP 0 LAST $SEC 1
J 0
(-3425 2675);
DISPLAY 0.680851 (-3425 2675);
PAINT MONO (-3425 2675);
DISPLAY INVISIBLE (-3425 2675);
FORCEPROP 0 LAST CDS_SEC 1
J 0
(-3425 2675);
DISPLAY 1.021277 (-3425 2675);
DISPLAY INVISIBLE (-3425 2675);
FORCEPROP 1 LASTPIN (-3475 2600) $PN 1
J 0
(-3470 2562);
DISPLAY 0.787234 (-3470 2562);
PAINT MONO (-3470 2562);
FORCEPROP 1 LASTPIN (-3475 2400) $PN 2
J 0
(-3470 2410);
DISPLAY 0.787234 (-3470 2410);
PAINT MONO (-3470 2410);
FORCEPROP 1 LAST WATTAGE 1/16W
J 0
(-3425 2450);
DISPLAY 0.510638 (-3425 2450);
FORCEPROP 1 LAST MATERIAL EMPTY
J 0
(-3425 2400);
DISPLAY 0.510638 (-3425 2400);
PAINT RED (-3425 2400);
FORCEPROP 1 LAST TOLERANCE 1%
J 0
(-3425 2500);
DISPLAY 0.510638 (-3425 2500);
FORCEPROP 1 LAST PACK_TYPE 0402LF
J 0
(-3425 2300);
DISPLAY 0.510638 (-3425 2300);
FORCEPROP 1 LAST VALUE 4.7K
J 0
(-3425 2550);
DISPLAY 0.510638 (-3425 2550);
FORCEPROP 0 LAST ROOM ADC_TI_BOM1
J 0
(-3425 2650);
DISPLAY 0.680851 (-3425 2650);
PAINT RED (-3425 2650);
FORCEPROP 2 LAST CDS_LIB pure_quanta
J 0
(-3475 2500);
DISPLAY INVISIBLE (-3475 2500);
FORCEPROP 1 LAST PATH I131
J 0
(-3425 2675);
DISPLAY 0.978723 (-3425 2675);
PAINT WHITE (-3425 2675);
DISPLAY INVISIBLE (-3425 2675);
FORCEPROP 1 LAST PART_NUMBER CS24702FB06
J 0
(-3425 2350);
DISPLAY 0.510638 (-3425 2350);
DISPLAY INVISIBLE (-3425 2350);
FORCEADD OFFPAGE..4
R 2
(-2750 1925);
FORCEPROP 2 LAST $XR0 258 
J 0
(-3032 1925);
DISPLAY 0.638298 (-3032 1925);
PAINT MONO (-3032 1925);
FORCEPROP 2 LAST CDS_LIB standard
J 2
(-2750 1925);
DISPLAY INVISIBLE (-2750 1925);
FORCEPROP 1 LAST OFFPAGE TRUE
J 2
(-3075 1800);
DISPLAY 0.872340 (-3075 1800);
DISPLAY INVISIBLE (-3075 1800);
FORCEPROP 1 LAST COMMENT_BODY TRUE
J 2
(-2725 1825);
DISPLAY 0.872340 (-2725 1825);
PAINT GREEN (-2725 1825);
DISPLAY INVISIBLE (-2725 1825);
FORCEPROP 2 LAST PATH I132
J 0
(-3000 1975);
DISPLAY 0.680851 (-3000 1975);
DISPLAY INVISIBLE (-3000 1975);
FORCEADD OFFPAGE..4
R 2
(-2750 1875);
FORCEPROP 2 LAST $XR0 258 
J 0
(-3032 1875);
DISPLAY 0.638298 (-3032 1875);
PAINT MONO (-3032 1875);
FORCEPROP 2 LAST CDS_LIB standard
J 2
(-2750 1875);
DISPLAY INVISIBLE (-2750 1875);
FORCEPROP 1 LAST OFFPAGE TRUE
J 2
(-3075 1750);
DISPLAY 0.872340 (-3075 1750);
DISPLAY INVISIBLE (-3075 1750);
FORCEPROP 1 LAST COMMENT_BODY TRUE
J 2
(-2725 1775);
DISPLAY 0.872340 (-2725 1775);
PAINT GREEN (-2725 1775);
DISPLAY INVISIBLE (-2725 1775);
FORCEPROP 2 LAST PATH I133
J 0
(-3000 1925);
DISPLAY 0.680851 (-3000 1925);
DISPLAY INVISIBLE (-3000 1925);
FORCEADD OFFPAGE..4
R 2
(-2750 1975);
FORCEPROP 2 LAST $XR0 258 
J 0
(-3032 1975);
DISPLAY 0.638298 (-3032 1975);
PAINT MONO (-3032 1975);
FORCEPROP 2 LAST CDS_LIB standard
J 2
(-2750 1975);
DISPLAY INVISIBLE (-2750 1975);
FORCEPROP 1 LAST OFFPAGE TRUE
J 2
(-3075 1850);
DISPLAY 0.872340 (-3075 1850);
DISPLAY INVISIBLE (-3075 1850);
FORCEPROP 1 LAST COMMENT_BODY TRUE
J 2
(-2725 1875);
DISPLAY 0.872340 (-2725 1875);
PAINT GREEN (-2725 1875);
DISPLAY INVISIBLE (-2725 1875);
FORCEPROP 2 LAST PATH I134
J 0
(-3000 2025);
DISPLAY 0.680851 (-3000 2025);
DISPLAY INVISIBLE (-3000 2025);
FORCEADD OFFPAGE..4
R 2
(-2750 2025);
FORCEPROP 2 LAST $XR0 258 
J 0
(-3032 2025);
DISPLAY 0.638298 (-3032 2025);
PAINT MONO (-3032 2025);
FORCEPROP 2 LAST CDS_LIB standard
J 2
(-2750 2025);
DISPLAY INVISIBLE (-2750 2025);
FORCEPROP 1 LAST OFFPAGE TRUE
J 2
(-3075 1900);
DISPLAY 0.872340 (-3075 1900);
DISPLAY INVISIBLE (-3075 1900);
FORCEPROP 1 LAST COMMENT_BODY TRUE
J 2
(-2725 1925);
DISPLAY 0.872340 (-2725 1925);
PAINT GREEN (-2725 1925);
DISPLAY INVISIBLE (-2725 1925);
FORCEPROP 2 LAST PATH I135
J 0
(-3000 2075);
DISPLAY 0.680851 (-3000 2075);
DISPLAY INVISIBLE (-3000 2075);
FORCEADD OFFPAGE..4
R 2
(-2750 2175);
FORCEPROP 2 LAST $XR0 258 
J 0
(-3032 2175);
DISPLAY 0.638298 (-3032 2175);
PAINT MONO (-3032 2175);
FORCEPROP 2 LAST CDS_LIB standard
J 2
(-2750 2175);
DISPLAY INVISIBLE (-2750 2175);
FORCEPROP 1 LAST OFFPAGE TRUE
J 2
(-3075 2050);
DISPLAY 0.872340 (-3075 2050);
DISPLAY INVISIBLE (-3075 2050);
FORCEPROP 1 LAST COMMENT_BODY TRUE
J 2
(-2725 2075);
DISPLAY 0.872340 (-2725 2075);
PAINT GREEN (-2725 2075);
DISPLAY INVISIBLE (-2725 2075);
FORCEPROP 2 LAST PATH I136
J 0
(-3000 2225);
DISPLAY 0.680851 (-3000 2225);
DISPLAY INVISIBLE (-3000 2225);
FORCEADD OFFPAGE..4
R 2
(-2750 2125);
FORCEPROP 2 LAST $XR0 258 
J 0
(-3032 2125);
DISPLAY 0.638298 (-3032 2125);
PAINT MONO (-3032 2125);
FORCEPROP 2 LAST CDS_LIB standard
J 2
(-2750 2125);
DISPLAY INVISIBLE (-2750 2125);
FORCEPROP 1 LAST OFFPAGE TRUE
J 2
(-3075 2000);
DISPLAY 0.872340 (-3075 2000);
DISPLAY INVISIBLE (-3075 2000);
FORCEPROP 1 LAST COMMENT_BODY TRUE
J 2
(-2725 2025);
DISPLAY 0.872340 (-2725 2025);
PAINT GREEN (-2725 2025);
DISPLAY INVISIBLE (-2725 2025);
FORCEPROP 2 LAST PATH I137
J 0
(-3000 2175);
DISPLAY 0.680851 (-3000 2175);
DISPLAY INVISIBLE (-3000 2175);
FORCEADD OFFPAGE..3
R 2
(-2750 2375);
FORCEPROP 2 LAST $XR0 258 
J 0
(-3060 2375);
DISPLAY 0.638298 (-3060 2375);
PAINT MONO (-3060 2375);
FORCEPROP 2 LAST CDS_LIB standard
J 2
(-2750 2375);
DISPLAY INVISIBLE (-2750 2375);
FORCEPROP 1 LAST OFFPAGE TRUE
J 2
(-3075 2250);
DISPLAY 0.872340 (-3075 2250);
PAINT GREEN (-3075 2250);
DISPLAY INVISIBLE (-3075 2250);
FORCEPROP 1 LAST COMMENT_BODY TRUE
J 2
(-2700 2275);
DISPLAY 0.872340 (-2700 2275);
PAINT GREEN (-2700 2275);
DISPLAY INVISIBLE (-2700 2275);
FORCEPROP 2 LAST PATH I138
J 0
(-3025 2425);
DISPLAY 0.680851 (-3025 2425);
DISPLAY INVISIBLE (-3025 2425);
FORCEADD OFFPAGE..4
R 2
(-2750 2425);
FORCEPROP 2 LAST $XR0 258 
J 0
(-3032 2425);
DISPLAY 0.638298 (-3032 2425);
PAINT MONO (-3032 2425);
FORCEPROP 2 LAST CDS_LIB standard
J 2
(-2750 2425);
DISPLAY INVISIBLE (-2750 2425);
FORCEPROP 1 LAST OFFPAGE TRUE
J 2
(-3075 2300);
DISPLAY 0.872340 (-3075 2300);
DISPLAY INVISIBLE (-3075 2300);
FORCEPROP 1 LAST COMMENT_BODY TRUE
J 2
(-2725 2325);
DISPLAY 0.872340 (-2725 2325);
PAINT GREEN (-2725 2325);
DISPLAY INVISIBLE (-2725 2325);
FORCEPROP 2 LAST PATH I139
J 0
(-3000 2475);
DISPLAY 0.680851 (-3000 2475);
DISPLAY INVISIBLE (-3000 2475);
FORCEADD Q_RES..2
(-8900 3200);
FORCEPROP 1 LAST LOCATION R1791
J 0
(-8850 3325);
DISPLAY 0.510638 (-8850 3325);
FORCEPROP 2 LAST $SEC 1
J 0
(-8850 3425);
DISPLAY 0.680851 (-8850 3425);
PAINT MONO (-8850 3425);
DISPLAY INVISIBLE (-8850 3425);
FORCEPROP 0 LAST CDS_SEC 1
J 0
(-8850 3350);
DISPLAY 1.021277 (-8850 3350);
DISPLAY INVISIBLE (-8850 3350);
FORCEPROP 1 LASTPIN (-8900 3300) $PN 1
J 0
(-8895 3262);
DISPLAY 0.787234 (-8895 3262);
PAINT MONO (-8895 3262);
FORCEPROP 1 LASTPIN (-8900 3100) $PN 2
J 0
(-8895 3110);
DISPLAY 0.787234 (-8895 3110);
PAINT MONO (-8895 3110);
FORCEPROP 1 LAST MATERIAL CHIP
J 0
(-8855 3125);
DISPLAY 0.510638 (-8855 3125);
FORCEPROP 1 LAST WATTAGE 1/16W
J 0
(-8855 3175);
DISPLAY 0.510638 (-8855 3175);
FORCEPROP 1 LAST TOLERANCE 1%
J 0
(-8850 3225);
DISPLAY 0.510638 (-8850 3225);
FORCEPROP 1 LAST VALUE 9.09K
J 0
(-8850 3275);
DISPLAY 0.510638 (-8850 3275);
FORCEPROP 1 LAST PACK_TYPE 0402LF
J 0
(-8845 3025);
DISPLAY 0.510638 (-8845 3025);
FORCEPROP 2 LAST CDS_LIB pure_quanta
J 0
(-8900 3200);
DISPLAY INVISIBLE (-8900 3200);
FORCEPROP 1 LAST PATH I14
J 0
(-8850 3375);
DISPLAY 0.978723 (-8850 3375);
PAINT WHITE (-8850 3375);
DISPLAY INVISIBLE (-8850 3375);
FORCEPROP 1 LAST PART_NUMBER CS29092FB05
J 0
(-8855 3075);
DISPLAY 0.510638 (-8855 3075);
DISPLAY INVISIBLE (-8855 3075);
FORCEADD OFFPAGE..1
(-2550 1000);
FORCEPROP 2 LAST $XR1 258 
J 0
(-2982 1000);
DISPLAY 0.638298 (-2982 1000);
PAINT MONO (-2982 1000);
FORCEPROP 2 LAST $XR0 151 
J 0
(-2862 1000);
DISPLAY 0.638298 (-2862 1000);
PAINT MONO (-2862 1000);
FORCEPROP 2 LAST CDS_LIB standard
J 0
(-2550 1000);
PAINT MONO (-2550 1000);
DISPLAY INVISIBLE (-2550 1000);
FORCEPROP 1 LAST OFFPAGE TRUE
J 0
(-2225 875);
DISPLAY 0.872340 (-2225 875);
PAINT GREEN (-2225 875);
DISPLAY INVISIBLE (-2225 875);
FORCEPROP 1 LAST COMMENT_BODY TRUE
J 0
(-2425 900);
DISPLAY 0.872340 (-2425 900);
PAINT GREEN (-2425 900);
DISPLAY INVISIBLE (-2425 900);
FORCEPROP 2 LAST PATH I140
J 0
(-2825 1050);
DISPLAY 0.680851 (-2825 1050);
DISPLAY INVISIBLE (-2825 1050);
FORCEADD OFFPAGE..3
R 2
(-2550 1050);
FORCEPROP 2 LAST $XR1 258 
J 0
(-2980 1050);
DISPLAY 0.638298 (-2980 1050);
PAINT MONO (-2980 1050);
FORCEPROP 2 LAST $XR0 151 
J 0
(-2860 1050);
DISPLAY 0.638298 (-2860 1050);
PAINT MONO (-2860 1050);
FORCEPROP 2 LAST CDS_LIB standard
J 0
(-2550 1050);
PAINT MONO (-2550 1050);
DISPLAY INVISIBLE (-2550 1050);
FORCEPROP 1 LAST OFFPAGE TRUE
J 2
(-2875 925);
DISPLAY 0.872340 (-2875 925);
DISPLAY INVISIBLE (-2875 925);
FORCEPROP 1 LAST COMMENT_BODY TRUE
J 2
(-2500 950);
DISPLAY 0.872340 (-2500 950);
PAINT GREEN (-2500 950);
DISPLAY INVISIBLE (-2500 950);
FORCEPROP 2 LAST PATH I141
J 0
(-2825 1100);
DISPLAY 0.680851 (-2825 1100);
DISPLAY INVISIBLE (-2825 1100);
FORCEADD ADC128D818CIMTXNOPB..1
(-1625 2100);
FORCEPROP 1 LAST LOCATION U269
J 0
(-1878 2753);
DISPLAY 0.723404 (-1878 2753);
PAINT GREEN (-1878 2753);
FORCEPROP 0 LAST $SEC 1
J 0
(-1875 2900);
DISPLAY 0.680851 (-1875 2900);
PAINT MONO (-1875 2900);
DISPLAY INVISIBLE (-1875 2900);
FORCEPROP 0 LAST CDS_SEC 1
J 0
(-1875 2900);
DISPLAY 1.021277 (-1875 2900);
DISPLAY INVISIBLE (-1875 2900);
FORCEPROP 0 LASTPIN (-2025 2125) $PN 7
J 2
(-2035 2135);
DISPLAY 0.680851 (-2035 2135);
PAINT MONO (-2035 2135);
FORCEPROP 0 LASTPIN (-2025 2175) $PN 8
J 2
(-2035 2185);
DISPLAY 0.680851 (-2035 2185);
PAINT MONO (-2035 2185);
FORCEPROP 0 LASTPIN (-1225 1675) $PN 4
J 0
(-1215 1685);
DISPLAY 0.680851 (-1215 1685);
PAINT MONO (-1215 1685);
FORCEPROP 0 LASTPIN (-2025 1675) $PN 16
J 2
(-2035 1685);
DISPLAY 0.680851 (-2035 1685);
PAINT MONO (-2035 1685);
FORCEPROP 0 LASTPIN (-2025 1725) $PN 15
J 2
(-2035 1735);
DISPLAY 0.680851 (-2035 1735);
PAINT MONO (-2035 1735);
FORCEPROP 0 LASTPIN (-2025 1775) $PN 14
J 2
(-2035 1785);
DISPLAY 0.680851 (-2035 1785);
PAINT MONO (-2035 1785);
FORCEPROP 0 LASTPIN (-2025 1825) $PN 13
J 2
(-2035 1835);
DISPLAY 0.680851 (-2035 1835);
PAINT MONO (-2035 1835);
FORCEPROP 0 LASTPIN (-2025 1875) $PN 12
J 2
(-2035 1885);
DISPLAY 0.680851 (-2035 1885);
PAINT MONO (-2035 1885);
FORCEPROP 0 LASTPIN (-2025 1925) $PN 11
J 2
(-2035 1935);
DISPLAY 0.680851 (-2035 1935);
PAINT MONO (-2035 1935);
FORCEPROP 0 LASTPIN (-2025 1975) $PN 10
J 2
(-2035 1985);
DISPLAY 0.680851 (-2035 1985);
PAINT MONO (-2035 1985);
FORCEPROP 0 LASTPIN (-2025 2025) $PN 9
J 2
(-2035 2035);
DISPLAY 0.680851 (-2035 2035);
PAINT MONO (-2035 2035);
FORCEPROP 0 LASTPIN (-1225 2525) $PN 6
J 0
(-1215 2535);
DISPLAY 0.680851 (-1215 2535);
PAINT MONO (-1215 2535);
FORCEPROP 0 LASTPIN (-2025 2425) $PN 3
J 2
(-2035 2435);
DISPLAY 0.680851 (-2035 2435);
PAINT MONO (-2035 2435);
FORCEPROP 0 LASTPIN (-2025 2375) $PN 2
J 2
(-2035 2385);
DISPLAY 0.680851 (-2035 2385);
PAINT MONO (-2035 2385);
FORCEPROP 0 LASTPIN (-2025 2525) $PN 5
J 2
(-2035 2535);
DISPLAY 0.680851 (-2035 2535);
PAINT MONO (-2035 2535);
FORCEPROP 0 LASTPIN (-2025 2275) $PN 1
J 2
(-2035 2285);
DISPLAY 0.680851 (-2035 2285);
PAINT MONO (-2035 2285);
FORCEPROP 2 LAST VALUE ADC128D818CIMTX/NOPB
J 0
(-1875 2800);
DISPLAY 1.021277 (-1875 2800);
FORCEPROP 1 LAST MATERIAL IC
J 0
(-1878 2580);
DISPLAY 0.723404 (-1878 2580);
PAINT RED (-1878 2580);
FORCEPROP 2 LAST PART_TYPE SMLF
J 0
(-1875 2850);
DISPLAY 1.021277 (-1875 2850);
FORCEPROP 0 LAST ROOM ADC_TI_BOM1
J 0
(-1875 2950);
DISPLAY 0.680851 (-1875 2950);
PAINT RED (-1875 2950);
FORCEPROP 1 LAST PIN_NAMES_ROTATE True
J 0
(-1625 2100);
DISPLAY 0.489362 (-1625 2100);
PAINT GREEN (-1625 2100);
DISPLAY INVISIBLE (-1625 2100);
FORCEPROP 1 LAST CDS_LMAN_SYM_OUTLINE -250,475,250,-475
J 0
(-1625 2100);
DISPLAY 0.468085 (-1625 2100);
PAINT GREEN (-1625 2100);
DISPLAY INVISIBLE (-1625 2100);
FORCEPROP 2 LAST CDS_LIB pure_quanta
J 0
(-1625 2100);
DISPLAY INVISIBLE (-1625 2100);
FORCEPROP 1 LAST PATH I142
J 0
(-1625 2100);
DISPLAY 0.723404 (-1625 2100);
PAINT GREEN (-1625 2100);
DISPLAY INVISIBLE (-1625 2100);
FORCEPROP 1 LAST PART_NUMBER AL000128K00
J 0
(-1878 2669);
DISPLAY 0.723404 (-1878 2669);
PAINT GREEN (-1878 2669);
DISPLAY INVISIBLE (-1878 2669);
FORCEADD OFFPAGE..1
(-3400 3650);
FORCEPROP 2 LAST $XR1 258 
J 0
(-3802 3650);
DISPLAY 0.638298 (-3802 3650);
PAINT MONO (-3802 3650);
FORCEPROP 2 LAST $XR0 151 
J 0
(-3682 3650);
DISPLAY 0.638298 (-3682 3650);
PAINT MONO (-3682 3650);
FORCEPROP 2 LAST CDS_LIB standard
J 0
(-3400 3650);
PAINT MONO (-3400 3650);
DISPLAY INVISIBLE (-3400 3650);
FORCEPROP 1 LAST OFFPAGE TRUE
J 0
(-3075 3525);
DISPLAY 0.872340 (-3075 3525);
PAINT GREEN (-3075 3525);
DISPLAY INVISIBLE (-3075 3525);
FORCEPROP 1 LAST COMMENT_BODY TRUE
J 0
(-3275 3550);
DISPLAY 0.872340 (-3275 3550);
PAINT GREEN (-3275 3550);
DISPLAY INVISIBLE (-3275 3550);
FORCEPROP 2 LAST PATH I143
J 0
(-3675 3700);
DISPLAY 0.680851 (-3675 3700);
DISPLAY INVISIBLE (-3675 3700);
FORCEADD OFFPAGE..3
R 2
(-3400 3700);
FORCEPROP 2 LAST $XR1 258 
J 0
(-3800 3700);
DISPLAY 0.638298 (-3800 3700);
PAINT MONO (-3800 3700);
FORCEPROP 2 LAST $XR0 151 
J 0
(-3680 3700);
DISPLAY 0.638298 (-3680 3700);
PAINT MONO (-3680 3700);
FORCEPROP 2 LAST CDS_LIB standard
J 0
(-3400 3700);
PAINT MONO (-3400 3700);
DISPLAY INVISIBLE (-3400 3700);
FORCEPROP 1 LAST OFFPAGE TRUE
J 2
(-3725 3575);
DISPLAY 0.872340 (-3725 3575);
DISPLAY INVISIBLE (-3725 3575);
FORCEPROP 1 LAST COMMENT_BODY TRUE
J 2
(-3350 3600);
DISPLAY 0.872340 (-3350 3600);
PAINT GREEN (-3350 3600);
DISPLAY INVISIBLE (-3350 3600);
FORCEPROP 2 LAST PATH I144
J 0
(-3675 3750);
DISPLAY 0.680851 (-3675 3750);
DISPLAY INVISIBLE (-3675 3750);
FORCEADD UNIVERSAL_GND..1
(-2925 4250);
FORCEPROP 3 LASTPIN (-2925 4300) SIG_NAME GND\g
J 0
(-2915 4310);
DISPLAY 0.659574 (-2915 4310);
PAINT MONO (-2915 4310);
DISPLAY INVISIBLE (-2915 4310);
FORCEPROP 2 LAST CDS_LIB pure_quanta_power
J 0
(-2925 4250);
DISPLAY INVISIBLE (-2925 4250);
FORCEPROP 1 LAST HDL_POWER GND
J 1
(-2900 4175);
DISPLAY 0.872340 (-2900 4175);
PAINT GREEN (-2900 4175);
DISPLAY INVISIBLE (-2900 4175);
FORCEPROP 1 LAST PATH I145
J 0
(-2850 4250);
DISPLAY 0.872340 (-2850 4250);
PAINT AQUA (-2850 4250);
DISPLAY INVISIBLE (-2850 4250);
FORCEADD Q_RES..1
(-2400 3700);
FORCEPROP 1 LAST LOCATION R1792
J 0
(-2600 3700);
DISPLAY 0.510638 (-2600 3700);
FORCEPROP 0 LAST $SEC 1
J 0
(-2175 3725);
DISPLAY 0.680851 (-2175 3725);
PAINT MONO (-2175 3725);
DISPLAY INVISIBLE (-2175 3725);
FORCEPROP 0 LAST CDS_SEC 1
J 0
(-2175 3725);
DISPLAY 1.021277 (-2175 3725);
DISPLAY INVISIBLE (-2175 3725);
FORCEPROP 1 LASTPIN (-2500 3700) $PN 1
J 0
(-2488 3712);
DISPLAY 0.787234 (-2488 3712);
PAINT MONO (-2488 3712);
FORCEPROP 1 LASTPIN (-2300 3700) $PN 2
J 0
(-2338 3712);
DISPLAY 0.787234 (-2338 3712);
PAINT MONO (-2338 3712);
FORCEPROP 1 LAST VALUE 0
J 2
(-2250 3700);
DISPLAY 0.404255 (-2250 3700);
FORCEPROP 1 LAST WATTAGE 1/16W
J 2
(-2275 3600);
DISPLAY 0.404255 (-2275 3600);
FORCEPROP 1 LAST PACK_TYPE 0402LF
J 0
(-2500 3600);
DISPLAY 0.404255 (-2500 3600);
FORCEPROP 1 LAST TOLERANCE 5%
J 0
(-2225 3700);
DISPLAY 0.404255 (-2225 3700);
FORCEPROP 0 LAST ROOM ADC_MAM_BOM2
J 0
(-2525 3750);
DISPLAY 0.553191 (-2525 3750);
PAINT RED (-2525 3750);
FORCEPROP 1 LAST MATERIAL EMPTY
J 0
(-2175 3700);
DISPLAY 0.404255 (-2175 3700);
FORCEPROP 2 LAST CDS_LIB pure_quanta
J 0
(-2400 3700);
DISPLAY INVISIBLE (-2400 3700);
FORCEPROP 1 LAST PATH I146
J 0
(-2450 3850);
DISPLAY 0.978723 (-2450 3850);
PAINT WHITE (-2450 3850);
DISPLAY INVISIBLE (-2450 3850);
FORCEPROP 1 LAST PART_NUMBER CS00002JB13
J 0
(-2500 3575);
DISPLAY 0.404255 (-2500 3575);
DISPLAY INVISIBLE (-2500 3575);
FORCEADD Q_RES..1
(-2400 3650);
FORCEPROP 1 LAST LOCATION R1793
J 0
(-2600 3650);
DISPLAY 0.510638 (-2600 3650);
FORCEPROP 0 LAST $SEC 1
J 0
(-2175 3675);
DISPLAY 0.680851 (-2175 3675);
PAINT MONO (-2175 3675);
DISPLAY INVISIBLE (-2175 3675);
FORCEPROP 0 LAST CDS_SEC 1
J 0
(-2175 3675);
DISPLAY 1.021277 (-2175 3675);
DISPLAY INVISIBLE (-2175 3675);
FORCEPROP 1 LASTPIN (-2500 3650) $PN 1
J 0
(-2488 3662);
DISPLAY 0.787234 (-2488 3662);
PAINT MONO (-2488 3662);
FORCEPROP 1 LASTPIN (-2300 3650) $PN 2
J 0
(-2338 3662);
DISPLAY 0.787234 (-2338 3662);
PAINT MONO (-2338 3662);
FORCEPROP 0 LAST ROOM ADC_MAM_BOM2
J 0
(-2525 3550);
DISPLAY 0.553191 (-2525 3550);
PAINT RED (-2525 3550);
FORCEPROP 1 LAST VALUE 0
J 2
(-2250 3650);
DISPLAY 0.404255 (-2250 3650);
FORCEPROP 1 LAST TOLERANCE 5%
J 0
(-2225 3650);
DISPLAY 0.404255 (-2225 3650);
FORCEPROP 1 LAST MATERIAL EMPTY
J 0
(-2175 3650);
DISPLAY 0.404255 (-2175 3650);
FORCEPROP 2 LAST CDS_LIB pure_quanta
J 0
(-2400 3650);
DISPLAY INVISIBLE (-2400 3650);
FORCEPROP 1 LAST PACK_TYPE 0402LF
J 0
(-2150 3650);
DISPLAY 0.510638 (-2150 3650);
DISPLAY INVISIBLE (-2150 3650);
FORCEPROP 1 LAST WATTAGE 1/16W
J 2
(-2300 3575);
DISPLAY 0.319149 (-2300 3575);
DISPLAY INVISIBLE (-2300 3575);
FORCEPROP 1 LAST PATH I147
J 0
(-2450 3800);
DISPLAY 0.978723 (-2450 3800);
PAINT WHITE (-2450 3800);
DISPLAY INVISIBLE (-2450 3800);
FORCEPROP 1 LAST PART_NUMBER CS00002JB13
J 0
(-2475 3600);
DISPLAY 0.319149 (-2475 3600);
DISPLAY INVISIBLE (-2475 3600);
FORCEADD UNIVERSAL_GND..1
(-1900 4300);
FORCEPROP 3 LASTPIN (-1900 4350) SIG_NAME GND\g
J 0
(-1890 4360);
DISPLAY 0.659574 (-1890 4360);
PAINT MONO (-1890 4360);
DISPLAY INVISIBLE (-1890 4360);
FORCEPROP 2 LAST CDS_LIB pure_quanta_power
J 0
(-1900 4300);
DISPLAY INVISIBLE (-1900 4300);
FORCEPROP 1 LAST HDL_POWER GND
J 1
(-1875 4225);
DISPLAY 0.872340 (-1875 4225);
PAINT GREEN (-1875 4225);
DISPLAY INVISIBLE (-1875 4225);
FORCEPROP 1 LAST PATH I148
J 0
(-1825 4300);
DISPLAY 0.872340 (-1825 4300);
PAINT AQUA (-1825 4300);
DISPLAY INVISIBLE (-1825 4300);
FORCEADD Q_RES..1
(-1550 1050);
FORCEPROP 1 LAST LOCATION R3671
J 0
(-1750 1050);
DISPLAY 0.510638 (-1750 1050);
FORCEPROP 0 LAST $SEC 1
J 0
(-1325 1075);
DISPLAY 0.680851 (-1325 1075);
PAINT MONO (-1325 1075);
DISPLAY INVISIBLE (-1325 1075);
FORCEPROP 0 LAST CDS_SEC 1
J 0
(-1325 1075);
DISPLAY 1.021277 (-1325 1075);
DISPLAY INVISIBLE (-1325 1075);
FORCEPROP 1 LASTPIN (-1650 1050) $PN 1
J 0
(-1638 1062);
DISPLAY 0.787234 (-1638 1062);
PAINT MONO (-1638 1062);
FORCEPROP 1 LASTPIN (-1450 1050) $PN 2
J 0
(-1488 1062);
DISPLAY 0.787234 (-1488 1062);
PAINT MONO (-1488 1062);
FORCEPROP 1 LAST VALUE 0
J 2
(-1400 1050);
DISPLAY 0.404255 (-1400 1050);
FORCEPROP 1 LAST TOLERANCE 5%
J 0
(-1375 1050);
DISPLAY 0.404255 (-1375 1050);
FORCEPROP 1 LAST WATTAGE 1/16W
J 2
(-1425 950);
DISPLAY 0.404255 (-1425 950);
FORCEPROP 1 LAST PACK_TYPE 0402LF
J 0
(-1650 950);
DISPLAY 0.404255 (-1650 950);
FORCEPROP 1 LAST MATERIAL CHIP
J 0
(-1325 1050);
DISPLAY 0.404255 (-1325 1050);
PAINT RED (-1325 1050);
FORCEPROP 0 LAST ROOM ADC_TI_BOM1
J 0
(-1875 1100);
DISPLAY 0.446809 (-1875 1100);
PAINT RED (-1875 1100);
FORCEPROP 2 LAST CDS_LIB pure_quanta
J 0
(-1550 1050);
DISPLAY INVISIBLE (-1550 1050);
FORCEPROP 1 LAST PATH I149
J 0
(-1600 1200);
DISPLAY 0.978723 (-1600 1200);
PAINT WHITE (-1600 1200);
DISPLAY INVISIBLE (-1600 1200);
FORCEPROP 1 LAST PART_NUMBER CS00002JB13
J 0
(-1650 925);
DISPLAY 0.404255 (-1650 925);
DISPLAY INVISIBLE (-1650 925);
FORCEADD Q_RES..2
(-8900 3750);
FORCEPROP 1 LAST LOCATION R3005
J 0
(-8855 3875);
DISPLAY 0.638298 (-8855 3875);
FORCEPROP 0 LAST $SEC 1
J 0
(-8850 3925);
DISPLAY 0.680851 (-8850 3925);
PAINT MONO (-8850 3925);
DISPLAY INVISIBLE (-8850 3925);
FORCEPROP 0 LAST CDS_SEC 1
J 0
(-8850 3900);
DISPLAY 1.021277 (-8850 3900);
DISPLAY INVISIBLE (-8850 3900);
FORCEPROP 1 LASTPIN (-8900 3850) $PN 1
J 0
(-8895 3812);
DISPLAY 0.787234 (-8895 3812);
PAINT MONO (-8895 3812);
FORCEPROP 1 LASTPIN (-8900 3650) $PN 2
J 0
(-8895 3660);
DISPLAY 0.787234 (-8895 3660);
PAINT MONO (-8895 3660);
FORCEPROP 1 LAST TOLERANCE 1%
J 0
(-8855 3775);
DISPLAY 0.510638 (-8855 3775);
FORCEPROP 1 LAST VALUE 18K
J 0
(-8855 3825);
DISPLAY 0.510638 (-8855 3825);
FORCEPROP 1 LAST PACK_TYPE 0402LF
J 0
(-8860 3575);
DISPLAY 0.510638 (-8860 3575);
FORCEPROP 1 LAST WATTAGE 1/16W
J 0
(-8860 3725);
DISPLAY 0.510638 (-8860 3725);
FORCEPROP 1 LAST MATERIAL CHIP
J 0
(-8860 3675);
DISPLAY 0.510638 (-8860 3675);
FORCEPROP 2 LAST CDS_LIB pure_quanta
J 0
(-8900 3750);
DISPLAY INVISIBLE (-8900 3750);
FORCEPROP 1 LAST PATH I15
J 0
(-8850 3925);
DISPLAY 0.978723 (-8850 3925);
PAINT WHITE (-8850 3925);
DISPLAY INVISIBLE (-8850 3925);
FORCEPROP 1 LAST PART_NUMBER CS31802FB04
J 0
(-8860 3625);
DISPLAY 0.510638 (-8860 3625);
DISPLAY INVISIBLE (-8860 3625);
FORCEADD Q_RES..1
(-1550 1000);
FORCEPROP 1 LAST LOCATION R3672
J 0
(-1750 1000);
DISPLAY 0.510638 (-1750 1000);
FORCEPROP 0 LAST $SEC 1
J 0
(-1325 1025);
DISPLAY 0.680851 (-1325 1025);
PAINT MONO (-1325 1025);
DISPLAY INVISIBLE (-1325 1025);
FORCEPROP 0 LAST CDS_SEC 1
J 0
(-1325 1025);
DISPLAY 1.021277 (-1325 1025);
DISPLAY INVISIBLE (-1325 1025);
FORCEPROP 1 LASTPIN (-1650 1000) $PN 1
J 0
(-1638 1012);
DISPLAY 0.787234 (-1638 1012);
PAINT MONO (-1638 1012);
FORCEPROP 1 LASTPIN (-1450 1000) $PN 2
J 0
(-1488 1012);
DISPLAY 0.787234 (-1488 1012);
PAINT MONO (-1488 1012);
FORCEPROP 1 LAST VALUE 0
J 2
(-1400 1000);
DISPLAY 0.404255 (-1400 1000);
FORCEPROP 1 LAST TOLERANCE 5%
J 0
(-1375 1000);
DISPLAY 0.404255 (-1375 1000);
FORCEPROP 1 LAST MATERIAL CHIP
J 0
(-1325 1000);
DISPLAY 0.404255 (-1325 1000);
PAINT RED (-1325 1000);
FORCEPROP 0 LAST ROOM ADC_TI_BOM1
J 0
(-1900 975);
DISPLAY 0.446809 (-1900 975);
PAINT RED (-1900 975);
FORCEPROP 1 LAST PACK_TYPE 0402LF
J 0
(-1300 1000);
DISPLAY 0.510638 (-1300 1000);
DISPLAY INVISIBLE (-1300 1000);
FORCEPROP 2 LAST CDS_LIB pure_quanta
J 0
(-1550 1000);
DISPLAY INVISIBLE (-1550 1000);
FORCEPROP 1 LAST WATTAGE 1/16W
J 2
(-1450 925);
DISPLAY 0.319149 (-1450 925);
DISPLAY INVISIBLE (-1450 925);
FORCEPROP 1 LAST PATH I150
J 0
(-1600 1150);
DISPLAY 0.978723 (-1600 1150);
PAINT WHITE (-1600 1150);
DISPLAY INVISIBLE (-1600 1150);
FORCEPROP 1 LAST PART_NUMBER CS00002JB13
J 0
(-1625 950);
DISPLAY 0.319149 (-1625 950);
DISPLAY INVISIBLE (-1625 950);
FORCEADD UNIVERSAL_GND..1
(-1050 1475);
FORCEPROP 3 LASTPIN (-1050 1525) SIG_NAME GND\g
J 0
(-1040 1535);
DISPLAY 0.659574 (-1040 1535);
PAINT MONO (-1040 1535);
DISPLAY INVISIBLE (-1040 1535);
FORCEPROP 2 LAST CDS_LIB pure_quanta_power
J 0
(-1050 1475);
DISPLAY INVISIBLE (-1050 1475);
FORCEPROP 1 LAST HDL_POWER GND
J 1
(-1025 1400);
DISPLAY 0.872340 (-1025 1400);
PAINT GREEN (-1025 1400);
DISPLAY INVISIBLE (-1025 1400);
FORCEPROP 1 LAST PATH I151
J 0
(-975 1475);
DISPLAY 0.872340 (-975 1475);
PAINT AQUA (-975 1475);
DISPLAY INVISIBLE (-975 1475);
FORCEADD OFFPAGE..3
(-500 1050);
FORCEPROP 2 LAST $XR0 258 
J 0
(-286 1050);
DISPLAY 0.638298 (-286 1050);
PAINT MONO (-286 1050);
FORCEPROP 2 LAST CDS_LIB standard
J 0
(-500 1050);
DISPLAY INVISIBLE (-500 1050);
FORCEPROP 1 LAST OFFPAGE TRUE
J 0
(-175 925);
DISPLAY 0.872340 (-175 925);
PAINT GREEN (-175 925);
DISPLAY INVISIBLE (-175 925);
FORCEPROP 1 LAST COMMENT_BODY TRUE
J 0
(-550 950);
DISPLAY 0.872340 (-550 950);
PAINT GREEN (-550 950);
DISPLAY INVISIBLE (-550 950);
FORCEPROP 2 LAST PATH I152
J 0
(-275 1100);
DISPLAY 0.680851 (-275 1100);
DISPLAY INVISIBLE (-275 1100);
FORCEADD OFFPAGE..2
(-500 1000);
FORCEPROP 2 LAST $XR0 258 
J 0
(-311 1000);
DISPLAY 0.638298 (-311 1000);
PAINT MONO (-311 1000);
FORCEPROP 2 LAST CDS_LIB standard
J 0
(-500 1000);
DISPLAY INVISIBLE (-500 1000);
FORCEPROP 1 LAST OFFPAGE TRUE
J 0
(-175 875);
DISPLAY 0.872340 (-175 875);
DISPLAY INVISIBLE (-175 875);
FORCEPROP 1 LAST COMMENT_BODY TRUE
J 0
(-545 905);
DISPLAY 0.872340 (-545 905);
PAINT GREEN (-545 905);
DISPLAY INVISIBLE (-545 905);
FORCEPROP 2 LAST PATH I153
J 0
(-300 1050);
DISPLAY 0.680851 (-300 1050);
DISPLAY INVISIBLE (-300 1050);
FORCEADD OFFPAGE..2
(-1350 3650);
FORCEPROP 2 LAST $XR0 258 
J 0
(-1131 3650);
DISPLAY 0.638298 (-1131 3650);
PAINT MONO (-1131 3650);
FORCEPROP 2 LAST CDS_LIB standard
J 0
(-1350 3650);
DISPLAY INVISIBLE (-1350 3650);
FORCEPROP 1 LAST OFFPAGE TRUE
J 0
(-1025 3525);
DISPLAY 0.872340 (-1025 3525);
DISPLAY INVISIBLE (-1025 3525);
FORCEPROP 1 LAST COMMENT_BODY TRUE
J 0
(-1395 3555);
DISPLAY 0.872340 (-1395 3555);
PAINT GREEN (-1395 3555);
DISPLAY INVISIBLE (-1395 3555);
FORCEPROP 2 LAST PATH I154
J 0
(-1125 3700);
DISPLAY 0.680851 (-1125 3700);
DISPLAY INVISIBLE (-1125 3700);
FORCEADD OFFPAGE..3
(-1350 3700);
FORCEPROP 2 LAST $XR0 258 
J 0
(-1136 3700);
DISPLAY 0.638298 (-1136 3700);
PAINT MONO (-1136 3700);
FORCEPROP 2 LAST CDS_LIB standard
J 0
(-1350 3700);
DISPLAY INVISIBLE (-1350 3700);
FORCEPROP 1 LAST OFFPAGE TRUE
J 0
(-1025 3575);
DISPLAY 0.872340 (-1025 3575);
PAINT GREEN (-1025 3575);
DISPLAY INVISIBLE (-1025 3575);
FORCEPROP 1 LAST COMMENT_BODY TRUE
J 0
(-1400 3600);
DISPLAY 0.872340 (-1400 3600);
PAINT GREEN (-1400 3600);
DISPLAY INVISIBLE (-1400 3600);
FORCEPROP 2 LAST PATH I155
J 0
(-1125 3750);
DISPLAY 0.680851 (-1125 3750);
DISPLAY INVISIBLE (-1125 3750);
FORCEADD OFFPAGE..4
(-1175 4550);
FORCEPROP 2 LAST $XR0 258 
J 0
(-989 4550);
DISPLAY 0.638298 (-989 4550);
PAINT MONO (-989 4550);
FORCEPROP 2 LAST CDS_LIB standard
J 2
(-1175 4550);
DISPLAY INVISIBLE (-1175 4550);
FORCEPROP 1 LAST OFFPAGE TRUE
J 0
(-850 4425);
DISPLAY 0.872340 (-850 4425);
DISPLAY INVISIBLE (-850 4425);
FORCEPROP 1 LAST COMMENT_BODY TRUE
J 0
(-1200 4450);
DISPLAY 0.872340 (-1200 4450);
PAINT GREEN (-1200 4450);
DISPLAY INVISIBLE (-1200 4450);
FORCEPROP 2 LAST PATH I156
J 0
(-975 4600);
DISPLAY 0.680851 (-975 4600);
DISPLAY INVISIBLE (-975 4600);
FORCEADD OFFPAGE..4
(-1175 4650);
FORCEPROP 2 LAST $XR0 258 
J 0
(-989 4650);
DISPLAY 0.638298 (-989 4650);
PAINT MONO (-989 4650);
FORCEPROP 2 LAST CDS_LIB standard
J 2
(-1175 4650);
DISPLAY INVISIBLE (-1175 4650);
FORCEPROP 1 LAST OFFPAGE TRUE
J 0
(-850 4525);
DISPLAY 0.872340 (-850 4525);
DISPLAY INVISIBLE (-850 4525);
FORCEPROP 1 LAST COMMENT_BODY TRUE
J 0
(-1200 4550);
DISPLAY 0.872340 (-1200 4550);
PAINT GREEN (-1200 4550);
DISPLAY INVISIBLE (-1200 4550);
FORCEPROP 2 LAST PATH I157
J 0
(-975 4700);
DISPLAY 0.680851 (-975 4700);
DISPLAY INVISIBLE (-975 4700);
FORCEADD OFFPAGE..1
R 2
(-1150 4750);
FORCEPROP 2 LAST $XR0 258 
J 0
(-964 4750);
DISPLAY 0.638298 (-964 4750);
PAINT MONO (-964 4750);
FORCEPROP 2 LAST CDS_LIB standard
J 2
(-1150 4750);
DISPLAY INVISIBLE (-1150 4750);
FORCEPROP 1 LAST OFFPAGE TRUE
J 2
(-1475 4625);
DISPLAY 0.872340 (-1475 4625);
PAINT GREEN (-1475 4625);
DISPLAY INVISIBLE (-1475 4625);
FORCEPROP 1 LAST COMMENT_BODY TRUE
J 2
(-1275 4650);
DISPLAY 0.872340 (-1275 4650);
PAINT GREEN (-1275 4650);
DISPLAY INVISIBLE (-1275 4650);
FORCEPROP 2 LAST PATH I158
J 0
(-950 4800);
DISPLAY 0.680851 (-950 4800);
DISPLAY INVISIBLE (-950 4800);
FORCEADD OFFPAGE..1
R 2
(-1150 4850);
FORCEPROP 2 LAST $XR0 258 
J 0
(-964 4850);
DISPLAY 0.638298 (-964 4850);
PAINT MONO (-964 4850);
FORCEPROP 2 LAST CDS_LIB standard
J 2
(-1150 4850);
DISPLAY INVISIBLE (-1150 4850);
FORCEPROP 1 LAST OFFPAGE TRUE
J 2
(-1475 4725);
DISPLAY 0.872340 (-1475 4725);
PAINT GREEN (-1475 4725);
DISPLAY INVISIBLE (-1475 4725);
FORCEPROP 1 LAST COMMENT_BODY TRUE
J 2
(-1275 4750);
DISPLAY 0.872340 (-1275 4750);
PAINT GREEN (-1275 4750);
DISPLAY INVISIBLE (-1275 4750);
FORCEPROP 2 LAST PATH I159
J 0
(-950 4900);
DISPLAY 0.680851 (-950 4900);
DISPLAY INVISIBLE (-950 4900);
FORCEADD Q_RES..1
(-8275 3350);
FORCEPROP 1 LAST LOCATION R3686
J 0
(-8450 3350);
DISPLAY 0.510638 (-8450 3350);
FORCEPROP 0 LAST $SEC 1
J 0
(-8400 3400);
DISPLAY 0.680851 (-8400 3400);
PAINT MONO (-8400 3400);
DISPLAY INVISIBLE (-8400 3400);
FORCEPROP 0 LAST CDS_SEC 1
J 0
(-8400 3400);
DISPLAY 1.021277 (-8400 3400);
DISPLAY INVISIBLE (-8400 3400);
FORCEPROP 1 LASTPIN (-8375 3350) $PN 1
J 0
(-8363 3362);
DISPLAY 0.787234 (-8363 3362);
PAINT MONO (-8363 3362);
FORCEPROP 1 LASTPIN (-8175 3350) $PN 2
J 0
(-8213 3362);
DISPLAY 0.787234 (-8213 3362);
PAINT MONO (-8213 3362);
FORCEPROP 0 LAST ROOM ADC_TI_BOM1
J 0
(-8350 3300);
DISPLAY 0.553191 (-8350 3300);
PAINT RED (-8350 3300);
FORCEPROP 1 LAST TOLERANCE 5%
J 0
(-8100 3350);
DISPLAY 0.404255 (-8100 3350);
FORCEPROP 1 LAST VALUE 0
J 2
(-8125 3350);
DISPLAY 0.404255 (-8125 3350);
FORCEPROP 1 LAST MATERIAL CHIP
J 0
(-8050 3350);
DISPLAY 0.404255 (-8050 3350);
PAINT RED (-8050 3350);
FORCEPROP 2 LAST CDS_LIB pure_quanta
J 0
(-8275 3350);
DISPLAY INVISIBLE (-8275 3350);
FORCEPROP 1 LAST WATTAGE 1/16W
J 2
(-8175 3275);
DISPLAY 0.319149 (-8175 3275);
DISPLAY INVISIBLE (-8175 3275);
FORCEPROP 1 LAST PACK_TYPE 0402LF
J 0
(-8025 3350);
DISPLAY 0.510638 (-8025 3350);
DISPLAY INVISIBLE (-8025 3350);
FORCEPROP 1 LAST PATH I16
J 0
(-8325 3500);
DISPLAY 0.978723 (-8325 3500);
PAINT WHITE (-8325 3500);
DISPLAY INVISIBLE (-8325 3500);
FORCEPROP 1 LAST PART_NUMBER CS00002JB13
J 0
(-8350 3300);
DISPLAY 0.319149 (-8350 3300);
DISPLAY INVISIBLE (-8350 3300);
FORCEADD Q_RES..1
(-3475 5525);
FORCEPROP 1 LAST LOCATION R2900
J 0
(-3725 5525);
DISPLAY 0.638298 (-3725 5525);
FORCEPROP 2 LAST $SEC 1
J 0
(-3275 5725);
DISPLAY 0.680851 (-3275 5725);
PAINT MONO (-3275 5725);
DISPLAY INVISIBLE (-3275 5725);
FORCEPROP 2 LAST CDS_SEC 1
J 0
(-3275 5725);
DISPLAY 1.021277 (-3275 5725);
DISPLAY INVISIBLE (-3275 5725);
FORCEPROP 1 LASTPIN (-3575 5525) $PN 1
J 0
(-3563 5537);
DISPLAY 0.787234 (-3563 5537);
FORCEPROP 1 LASTPIN (-3375 5525) $PN 2
J 0
(-3413 5537);
DISPLAY 0.787234 (-3413 5537);
FORCEPROP 1 LAST WATTAGE 1/16W
J 2
(-3275 5675);
DISPLAY 0.638298 (-3275 5675);
FORCEPROP 1 LAST VALUE 2K
J 2
(-3300 5525);
DISPLAY 0.638298 (-3300 5525);
FORCEPROP 1 LAST TOLERANCE 1%
J 0
(-3275 5525);
DISPLAY 0.638298 (-3275 5525);
FORCEPROP 1 LAST PACK_TYPE 0402LF
J 0
(-3650 5675);
DISPLAY 0.638298 (-3650 5675);
FORCEPROP 1 LAST MATERIAL CHIP
J 0
(-3200 5525);
DISPLAY 0.638298 (-3200 5525);
FORCEPROP 2 LAST CDS_LIB pure_quanta
J 0
(-3475 5525);
PAINT MONO (-3475 5525);
DISPLAY INVISIBLE (-3475 5525);
FORCEPROP 1 LAST PATH I160
J 0
(-3525 5675);
DISPLAY 0.978723 (-3525 5675);
PAINT WHITE (-3525 5675);
DISPLAY INVISIBLE (-3525 5675);
FORCEPROP 1 LAST PART_NUMBER CS22002FB07
J 0
(-3650 5625);
DISPLAY 0.638298 (-3650 5625);
DISPLAY INVISIBLE (-3650 5625);
FORCEADD UNIVERSAL_GND..1
(-1500 5150);
FORCEPROP 3 LASTPIN (-1500 5200) SIG_NAME GND\g
J 0
(-1490 5210);
DISPLAY 0.659574 (-1490 5210);
PAINT MONO (-1490 5210);
DISPLAY INVISIBLE (-1490 5210);
FORCEPROP 2 LAST CDS_LIB pure_quanta_power
J 0
(-1500 5150);
DISPLAY INVISIBLE (-1500 5150);
FORCEPROP 1 LAST HDL_POWER GND
J 1
(-1475 5075);
DISPLAY 0.872340 (-1475 5075);
PAINT GREEN (-1475 5075);
DISPLAY INVISIBLE (-1475 5075);
FORCEPROP 1 LAST PATH I161
J 0
(-1425 5150);
DISPLAY 0.872340 (-1425 5150);
PAINT AQUA (-1425 5150);
DISPLAY INVISIBLE (-1425 5150);
FORCEADD Q_CAP..1
R 2
(-1500 5325);
FORCEPROP 1 LAST LOCATION C1757
J 2
(-1325 5450);
DISPLAY 0.638298 (-1325 5450);
FORCEPROP 0 LAST $SEC 1
J 0
(-1550 5475);
DISPLAY 0.680851 (-1550 5475);
PAINT MONO (-1550 5475);
DISPLAY INVISIBLE (-1550 5475);
FORCEPROP 0 LAST CDS_SEC 1
J 0
(-1550 5475);
DISPLAY 1.021277 (-1550 5475);
DISPLAY INVISIBLE (-1550 5475);
FORCEPROP 1 LASTPIN (-1500 5425) $PN 1
J 2
(-1510 5405);
DISPLAY 0.787234 (-1510 5405);
PAINT MONO (-1510 5405);
FORCEPROP 1 LASTPIN (-1500 5225) $PN 2
J 2
(-1510 5205);
DISPLAY 0.787234 (-1510 5205);
PAINT MONO (-1510 5205);
FORCEPROP 1 LAST PACK_TYPE 0402
J 2
(-1325 5150);
DISPLAY 0.510638 (-1325 5150);
FORCEPROP 1 LAST VOLTAGE 25V
J 2
(-1350 5350);
DISPLAY 0.510638 (-1350 5350);
FORCEPROP 1 LAST VALUE 0.1UF
J 2
(-1325 5400);
DISPLAY 0.510638 (-1325 5400);
FORCEPROP 1 LAST MATERIAL X7R
J 2
(-1350 5250);
DISPLAY 0.510638 (-1350 5250);
FORCEPROP 1 LAST TOLERANCE 10%
J 2
(-1350 5300);
DISPLAY 0.510638 (-1350 5300);
FORCEPROP 2 LAST CDS_LIB pure_quanta
J 0
(-1500 5325);
DISPLAY INVISIBLE (-1500 5325);
FORCEPROP 1 LAST PATH I162
J 2
(-1550 5475);
DISPLAY 0.978723 (-1550 5475);
PAINT WHITE (-1550 5475);
DISPLAY INVISIBLE (-1550 5475);
FORCEPROP 1 LAST PART_NUMBER CH4104K1B00
J 2
(-1200 5200);
DISPLAY 0.510638 (-1200 5200);
DISPLAY INVISIBLE (-1200 5200);
FORCEADD UNIVERSAL_GND..1
(-1125 5150);
FORCEPROP 3 LASTPIN (-1125 5200) SIG_NAME GND\g
J 0
(-1115 5210);
DISPLAY 0.659574 (-1115 5210);
PAINT MONO (-1115 5210);
DISPLAY INVISIBLE (-1115 5210);
FORCEPROP 2 LAST CDS_LIB pure_quanta_power
J 0
(-1125 5150);
DISPLAY INVISIBLE (-1125 5150);
FORCEPROP 1 LAST HDL_POWER GND
J 1
(-1100 5075);
DISPLAY 0.872340 (-1100 5075);
PAINT GREEN (-1100 5075);
DISPLAY INVISIBLE (-1100 5075);
FORCEPROP 1 LAST PATH I163
J 0
(-1050 5150);
DISPLAY 0.872340 (-1050 5150);
PAINT AQUA (-1050 5150);
DISPLAY INVISIBLE (-1050 5150);
FORCEADD OFFPAGE..1
R 2
(-1050 4950);
FORCEPROP 2 LAST $XR0 258 
J 0
(-864 4950);
DISPLAY 0.638298 (-864 4950);
PAINT MONO (-864 4950);
FORCEPROP 2 LAST CDS_LIB standard
J 2
(-1050 4950);
DISPLAY INVISIBLE (-1050 4950);
FORCEPROP 1 LAST OFFPAGE TRUE
J 2
(-1375 4825);
DISPLAY 0.872340 (-1375 4825);
PAINT GREEN (-1375 4825);
DISPLAY INVISIBLE (-1375 4825);
FORCEPROP 1 LAST COMMENT_BODY TRUE
J 2
(-1175 4850);
DISPLAY 0.872340 (-1175 4850);
PAINT GREEN (-1175 4850);
DISPLAY INVISIBLE (-1175 4850);
FORCEPROP 2 LAST PATH I164
J 0
(-850 5000);
DISPLAY 0.680851 (-850 5000);
DISPLAY INVISIBLE (-850 5000);
FORCEADD OFFPAGE..1
R 2
(-1050 5050);
FORCEPROP 2 LAST $XR0 258 
J 0
(-864 5050);
DISPLAY 0.638298 (-864 5050);
PAINT MONO (-864 5050);
FORCEPROP 2 LAST CDS_LIB standard
J 0
(-1050 5050);
DISPLAY INVISIBLE (-1050 5050);
FORCEPROP 1 LAST OFFPAGE TRUE
J 2
(-1375 4925);
DISPLAY 0.872340 (-1375 4925);
PAINT GREEN (-1375 4925);
DISPLAY INVISIBLE (-1375 4925);
FORCEPROP 1 LAST COMMENT_BODY TRUE
J 2
(-1175 4950);
DISPLAY 0.872340 (-1175 4950);
PAINT GREEN (-1175 4950);
DISPLAY INVISIBLE (-1175 4950);
FORCEPROP 2 LAST PATH I165
J 0
(-850 5100);
DISPLAY 0.680851 (-850 5100);
DISPLAY INVISIBLE (-850 5100);
FORCEADD Q_CAP..1
(-1125 5325);
FORCEPROP 1 LAST LOCATION C1768
J 0
(-1075 5425);
DISPLAY 0.510638 (-1075 5425);
FORCEPROP 2 LAST $SEC 1
J 0
(-1075 5525);
DISPLAY 0.680851 (-1075 5525);
PAINT MONO (-1075 5525);
DISPLAY INVISIBLE (-1075 5525);
FORCEPROP 2 LAST CDS_SEC 1
J 0
(-1075 5525);
DISPLAY 1.021277 (-1075 5525);
DISPLAY INVISIBLE (-1075 5525);
FORCEPROP 1 LASTPIN (-1125 5425) $PN 1
J 0
(-1115 5405);
DISPLAY 0.787234 (-1115 5405);
FORCEPROP 1 LASTPIN (-1125 5225) $PN 2
J 0
(-1115 5205);
DISPLAY 0.787234 (-1115 5205);
FORCEPROP 1 LAST VALUE 10UF
J 0
(-1075 5375);
DISPLAY 0.510638 (-1075 5375);
FORCEPROP 1 LAST PACK_TYPE C0805
J 0
(-1075 5125);
DISPLAY 0.510638 (-1075 5125);
FORCEPROP 1 LAST TOLERANCE 10%
J 0
(-1075 5275);
DISPLAY 0.510638 (-1075 5275);
FORCEPROP 1 LAST VOLTAGE 16V
J 0
(-1075 5325);
DISPLAY 0.510638 (-1075 5325);
FORCEPROP 1 LAST MATERIAL X6S
J 0
(-1075 5225);
DISPLAY 0.510638 (-1075 5225);
FORCEPROP 2 LAST CDS_LIB pure_quanta
J 0
(-1125 5325);
PAINT MONO (-1125 5325);
DISPLAY INVISIBLE (-1125 5325);
FORCEPROP 1 LAST PATH I166
J 0
(-1075 5475);
DISPLAY 0.978723 (-1075 5475);
PAINT WHITE (-1075 5475);
DISPLAY INVISIBLE (-1075 5475);
FORCEPROP 1 LAST PART_NUMBER CH6103KEA00
J 0
(-1075 5175);
DISPLAY 0.510638 (-1075 5175);
DISPLAY INVISIBLE (-1075 5175);
FORCEADD Q_INDUCTOR..1
(-800 5550);
FORCEPROP 1 LAST LOCATION L15
J 0
(-900 5710);
DISPLAY 0.382979 (-900 5710);
PAINT GREEN (-900 5710);
FORCEPROP 2 LAST $SEC 1
J 0
(-900 5825);
DISPLAY 0.680851 (-900 5825);
PAINT MONO (-900 5825);
DISPLAY INVISIBLE (-900 5825);
FORCEPROP 2 LAST CDS_SEC 1
J 0
(-900 5825);
DISPLAY 1.021277 (-900 5825);
DISPLAY INVISIBLE (-900 5825);
FORCEPROP 2 LASTPIN (-900 5525) $PN 1
J 2
(-910 5535);
DISPLAY 0.680851 (-910 5535);
PAINT MONO (-910 5535);
FORCEPROP 2 LASTPIN (-700 5525) $PN 2
J 0
(-690 5535);
DISPLAY 0.680851 (-690 5535);
PAINT MONO (-690 5535);
FORCEPROP 2 LAST VALUE BLM18PG300SN1D 
J 0
(-900 5800);
DISPLAY 0.510638 (-900 5800);
FORCEPROP 2 LAST PACK_TYPE SMLF
J 0
(-900 5750);
DISPLAY 0.510638 (-900 5750);
FORCEPROP 1 LAST MATERIAL IND
J 0
(-900 5605);
DISPLAY 0.382979 (-900 5605);
PAINT GREEN (-900 5605);
FORCEPROP 2 LAST CDS_LIB pure_quanta
J 0
(-800 5550);
DISPLAY INVISIBLE (-800 5550);
FORCEPROP 1 LAST NEEDS_NO_SIZE TRUE
J 0
(-800 5550);
DISPLAY 0.468085 (-800 5550);
PAINT GREEN (-800 5550);
DISPLAY INVISIBLE (-800 5550);
FORCEPROP 1 LAST PATH I167
J 0
(-725 5605);
DISPLAY 0.723404 (-725 5605);
PAINT GREEN (-725 5605);
DISPLAY INVISIBLE (-725 5605);
FORCEPROP 1 LAST PART_NUMBER TMP_QCX8PG300001
J 0
(-900 5660);
DISPLAY 0.382979 (-900 5660);
PAINT GREEN (-900 5660);
DISPLAY INVISIBLE (-900 5660);
FORCEADD UNIVERSAL_POWER..1
(-375 5750);
FORCEPROP 3 LASTPIN (-375 5700) SIG_NAME P3V3_AUX\g
J 0
(-365 5710);
DISPLAY 0.659574 (-365 5710);
PAINT MONO (-365 5710);
DISPLAY INVISIBLE (-365 5710);
FORCEPROP 1 LAST HDL_POWER P3V3_AUX
J 1
(-375 5800);
DISPLAY 0.872340 (-375 5800);
PAINT GREEN (-375 5800);
FORCEPROP 2 LAST CDS_LIB pure_quanta_power
J 0
(-375 5750);
DISPLAY INVISIBLE (-375 5750);
FORCEPROP 1 LAST PATH I168
J 0
(-325 5775);
DISPLAY 0.872340 (-325 5775);
PAINT AQUA (-325 5775);
DISPLAY INVISIBLE (-325 5775);
FORCEADD MAX11617EEET..1
(-2425 4900);
FORCEPROP 1 LAST LOCATION U193
J 0
(-2670 5581);
DISPLAY 0.723404 (-2670 5581);
PAINT GREEN (-2670 5581);
FORCEPROP 2 LAST SEC 1
J 0
(-2650 5725);
DISPLAY 0.680851 (-2650 5725);
PAINT MONO (-2650 5725);
DISPLAY INVISIBLE (-2650 5725);
FORCEPROP 2 LASTPIN (-2825 4850) $PN 5
J 2
(-2835 4860);
DISPLAY 0.680851 (-2835 4860);
PAINT MONO (-2835 4860);
FORCEPROP 2 LASTPIN (-2825 4750) $PN 6
J 2
(-2835 4760);
DISPLAY 0.680851 (-2835 4760);
PAINT MONO (-2835 4760);
FORCEPROP 2 LASTPIN (-2825 4650) $PN 7
J 2
(-2835 4660);
DISPLAY 0.680851 (-2835 4660);
PAINT MONO (-2835 4660);
FORCEPROP 2 LASTPIN (-2825 4550) $PN 8
J 2
(-2835 4560);
DISPLAY 0.680851 (-2835 4560);
PAINT MONO (-2835 4560);
FORCEPROP 2 LASTPIN (-2025 4550) $PN 9
J 0
(-2015 4560);
DISPLAY 0.680851 (-2015 4560);
PAINT MONO (-2015 4560);
FORCEPROP 2 LASTPIN (-2025 4650) $PN 10
J 0
(-2015 4660);
DISPLAY 0.680851 (-2015 4660);
PAINT MONO (-2015 4660);
FORCEPROP 2 LASTPIN (-2025 4750) $PN 11
J 0
(-2015 4760);
DISPLAY 0.680851 (-2015 4760);
PAINT MONO (-2015 4760);
FORCEPROP 2 LASTPIN (-2025 4850) $PN 12
J 0
(-2015 4860);
DISPLAY 0.680851 (-2015 4860);
PAINT MONO (-2015 4860);
FORCEPROP 2 LASTPIN (-2825 4950) $PN 4
J 2
(-2835 4960);
DISPLAY 0.680851 (-2835 4960);
PAINT MONO (-2835 4960);
FORCEPROP 2 LASTPIN (-2825 5050) $PN 3
J 2
(-2835 5060);
DISPLAY 0.680851 (-2835 5060);
PAINT MONO (-2835 5060);
FORCEPROP 2 LASTPIN (-2825 5150) $PN 2
J 2
(-2835 5160);
DISPLAY 0.680851 (-2835 5160);
PAINT MONO (-2835 5160);
FORCEPROP 2 LASTPIN (-2825 5250) $PN 1
J 2
(-2835 5260);
DISPLAY 0.680851 (-2835 5260);
PAINT MONO (-2835 5260);
FORCEPROP 2 LASTPIN (-2025 5150) $PN 15
J 0
(-2015 5160);
DISPLAY 0.680851 (-2015 5160);
PAINT MONO (-2015 5160);
FORCEPROP 2 LASTPIN (-2025 4950) $PN 13
J 0
(-2015 4960);
DISPLAY 0.680851 (-2015 4960);
PAINT MONO (-2015 4960);
FORCEPROP 2 LASTPIN (-2025 5050) $PN 14
J 0
(-2015 5060);
DISPLAY 0.680851 (-2015 5060);
PAINT MONO (-2015 5060);
FORCEPROP 2 LASTPIN (-2025 5250) $PN 16
J 0
(-2015 5260);
DISPLAY 0.680851 (-2015 5260);
PAINT MONO (-2015 5260);
FORCEPROP 1 LAST MATERIAL EMPTY
J 0
(-2670 5307);
DISPLAY 0.723404 (-2670 5307);
PAINT GREEN (-2670 5307);
FORCEPROP 0 LAST ROOM ADC_MAM_BOM2
J 0
(-2650 5775);
DISPLAY 0.680851 (-2650 5775);
PAINT RED (-2650 5775);
FORCEPROP 2 LAST VALUE MAX11617EEE+T
J 0
(-2650 5625);
DISPLAY 1.021277 (-2650 5625);
FORCEPROP 2 LAST PART_TYPE SMLF
J 0
(-2650 5675);
DISPLAY 1.021277 (-2650 5675);
FORCEPROP 2 LAST SEC_TYPE 
J 0
(-2650 5725);
DISPLAY 1.021277 (-2650 5725);
DISPLAY INVISIBLE (-2650 5725);
FORCEPROP 1 LAST CDS_LMAN_SYM_OUTLINE -250,400,250,-400
J 0
(-2425 4900);
DISPLAY 0.468085 (-2425 4900);
PAINT GREEN (-2425 4900);
DISPLAY INVISIBLE (-2425 4900);
FORCEPROP 1 LAST NEEDS_NO_SIZE TRUE
J 0
(-2425 4900);
DISPLAY 0.723404 (-2425 4900);
PAINT GREEN (-2425 4900);
DISPLAY INVISIBLE (-2425 4900);
FORCEPROP 2 LAST CDS_LIB pure_quanta
J 0
(-2425 4900);
DISPLAY INVISIBLE (-2425 4900);
FORCEPROP 1 LAST PATH I169
J 0
(-2425 4900);
DISPLAY 0.723404 (-2425 4900);
PAINT GREEN (-2425 4900);
DISPLAY INVISIBLE (-2425 4900);
FORCEPROP 1 LAST PART_NUMBER AL011617W00
J 0
(-2670 5434);
DISPLAY 0.723404 (-2670 5434);
PAINT GREEN (-2670 5434);
DISPLAY INVISIBLE (-2670 5434);
FORCEADD Q_CAP..1
R 2
(-7925 3075);
FORCEPROP 1 LAST LOCATION C2049
J 2
(-7775 3175);
DISPLAY 0.638298 (-7775 3175);
FORCEPROP 0 LAST $SEC 1
J 0
(-7825 3225);
DISPLAY 0.680851 (-7825 3225);
PAINT MONO (-7825 3225);
DISPLAY INVISIBLE (-7825 3225);
FORCEPROP 0 LAST CDS_SEC 1
J 0
(-7825 3225);
DISPLAY 1.021277 (-7825 3225);
DISPLAY INVISIBLE (-7825 3225);
FORCEPROP 1 LASTPIN (-7925 3175) $PN 1
J 2
(-7935 3155);
DISPLAY 0.787234 (-7935 3155);
PAINT MONO (-7935 3155);
FORCEPROP 1 LASTPIN (-7925 2975) $PN 2
J 2
(-7935 2955);
DISPLAY 0.787234 (-7935 2955);
PAINT MONO (-7935 2955);
FORCEPROP 1 LAST VALUE 0.1UF
J 2
(-7750 3150);
DISPLAY 0.510638 (-7750 3150);
FORCEPROP 1 LAST VOLTAGE 25V
J 2
(-7775 3100);
DISPLAY 0.510638 (-7775 3100);
FORCEPROP 1 LAST TOLERANCE 10%
J 2
(-7775 3050);
DISPLAY 0.510638 (-7775 3050);
FORCEPROP 1 LAST MATERIAL X7R
J 2
(-7775 3000);
DISPLAY 0.510638 (-7775 3000);
PAINT RED (-7775 3000);
FORCEPROP 1 LAST PACK_TYPE 0402
J 2
(-7750 2900);
DISPLAY 0.510638 (-7750 2900);
FORCEPROP 0 LAST ROOM ADC_TI_BOM1
J 0
(-7900 2875);
DISPLAY 0.553191 (-7900 2875);
PAINT RED (-7900 2875);
FORCEPROP 2 LAST CDS_LIB pure_quanta
J 0
(-7925 3075);
DISPLAY INVISIBLE (-7925 3075);
FORCEPROP 1 LAST PATH I17
J 2
(-7975 3225);
DISPLAY 0.978723 (-7975 3225);
PAINT WHITE (-7975 3225);
DISPLAY INVISIBLE (-7975 3225);
FORCEPROP 1 LAST PART_NUMBER CH4104K1B00
J 2
(-7625 2950);
DISPLAY 0.510638 (-7625 2950);
DISPLAY INVISIBLE (-7625 2950);
FORCEADD Q_RES..2
(-8925 2000);
FORCEPROP 1 LAST LOCATION R1800
J 0
(-8880 2125);
DISPLAY 0.638298 (-8880 2125);
FORCEPROP 2 LAST SEC 1
J 0
(-8875 2225);
DISPLAY 0.680851 (-8875 2225);
PAINT MONO (-8875 2225);
DISPLAY INVISIBLE (-8875 2225);
FORCEPROP 1 LASTPIN (-8925 2100) $PN 1
J 0
(-8920 2062);
DISPLAY 0.787234 (-8920 2062);
PAINT MONO (-8920 2062);
FORCEPROP 1 LASTPIN (-8925 1900) $PN 2
J 0
(-8920 1910);
DISPLAY 0.787234 (-8920 1910);
PAINT MONO (-8920 1910);
FORCEPROP 1 LAST TOLERANCE 1%
J 0
(-8880 2025);
DISPLAY 0.638298 (-8880 2025);
FORCEPROP 1 LAST MATERIAL CHIP
J 0
(-8885 1925);
DISPLAY 0.638298 (-8885 1925);
FORCEPROP 1 LAST PACK_TYPE 0402LF
J 0
(-8885 1825);
DISPLAY 0.638298 (-8885 1825);
FORCEPROP 1 LAST WATTAGE 1/16W
J 0
(-8885 1975);
DISPLAY 0.638298 (-8885 1975);
FORCEPROP 1 LAST VALUE 1.21K
J 0
(-8880 2075);
DISPLAY 0.638298 (-8880 2075);
FORCEPROP 2 LAST CDS_LIB pure_quanta
J 0
(-8925 2000);
DISPLAY INVISIBLE (-8925 2000);
FORCEPROP 2 LAST SEC_TYPE 0402LF
J 0
(-8875 2225);
DISPLAY 0.680851 (-8875 2225);
DISPLAY INVISIBLE (-8875 2225);
FORCEPROP 1 LAST PATH I170
J 0
(-8875 2175);
DISPLAY 0.978723 (-8875 2175);
PAINT WHITE (-8875 2175);
DISPLAY INVISIBLE (-8875 2175);
FORCEPROP 1 LAST PART_NUMBER CS21212FB05
J 0
(-8885 1875);
DISPLAY 0.638298 (-8885 1875);
DISPLAY INVISIBLE (-8885 1875);
FORCEADD Q_RES..1
(-8275 3500);
FORCEPROP 1 LAST LOCATION R3685
J 0
(-8450 3500);
DISPLAY 0.510638 (-8450 3500);
FORCEPROP 0 LAST $SEC 1
J 0
(-8400 3550);
DISPLAY 0.680851 (-8400 3550);
PAINT MONO (-8400 3550);
DISPLAY INVISIBLE (-8400 3550);
FORCEPROP 0 LAST CDS_SEC 1
J 0
(-8400 3550);
DISPLAY 1.021277 (-8400 3550);
DISPLAY INVISIBLE (-8400 3550);
FORCEPROP 1 LASTPIN (-8375 3500) $PN 1
J 0
(-8363 3512);
DISPLAY 0.787234 (-8363 3512);
PAINT MONO (-8363 3512);
FORCEPROP 1 LASTPIN (-8175 3500) $PN 2
J 0
(-8213 3512);
DISPLAY 0.787234 (-8213 3512);
PAINT MONO (-8213 3512);
FORCEPROP 1 LAST VALUE 0
J 2
(-8125 3500);
DISPLAY 0.404255 (-8125 3500);
FORCEPROP 0 LAST ROOM ADC_MAM_BOM2
J 0
(-8400 3625);
DISPLAY 0.553191 (-8400 3625);
PAINT RED (-8400 3625);
FORCEPROP 1 LAST MATERIAL EMPTY
J 0
(-8050 3500);
DISPLAY 0.404255 (-8050 3500);
FORCEPROP 1 LAST TOLERANCE 5%
J 0
(-8100 3500);
DISPLAY 0.404255 (-8100 3500);
FORCEPROP 2 LAST CDS_LIB pure_quanta
J 0
(-8275 3500);
DISPLAY INVISIBLE (-8275 3500);
FORCEPROP 1 LAST WATTAGE 1/16W
J 2
(-8175 3425);
DISPLAY 0.319149 (-8175 3425);
DISPLAY INVISIBLE (-8175 3425);
FORCEPROP 1 LAST PACK_TYPE 0402LF
J 0
(-8025 3500);
DISPLAY 0.510638 (-8025 3500);
DISPLAY INVISIBLE (-8025 3500);
FORCEPROP 1 LAST PATH I18
J 0
(-8325 3650);
DISPLAY 0.978723 (-8325 3650);
PAINT WHITE (-8325 3650);
DISPLAY INVISIBLE (-8325 3650);
FORCEPROP 1 LAST PART_NUMBER CS00002JB13
J 0
(-8350 3450);
DISPLAY 0.319149 (-8350 3450);
DISPLAY INVISIBLE (-8350 3450);
FORCEADD UNIVERSAL_POWER..1
(-8900 4000);
FORCEPROP 3 LASTPIN (-8900 3950) SIG_NAME P5V\g
J 0
(-8890 3960);
DISPLAY 0.659574 (-8890 3960);
PAINT MONO (-8890 3960);
DISPLAY INVISIBLE (-8890 3960);
FORCEPROP 1 LAST HDL_POWER P5V
J 1
(-8900 4050);
DISPLAY 0.872340 (-8900 4050);
PAINT GREEN (-8900 4050);
FORCEPROP 2 LAST CDS_LIB pure_quanta_power
J 0
(-8900 4000);
DISPLAY INVISIBLE (-8900 4000);
FORCEPROP 1 LAST PATH I19
J 0
(-8850 4025);
DISPLAY 0.872340 (-8850 4025);
PAINT AQUA (-8850 4025);
DISPLAY INVISIBLE (-8850 4025);
FORCEADD OFFPAGE..1
(-9050 1550);
FORCEPROP 2 LAST $XR0 241 
J 0
(-9332 1550);
DISPLAY 0.638298 (-9332 1550);
PAINT MONO (-9332 1550);
FORCEPROP 2 LAST CDS_LIB standard
J 0
(-9050 1550);
DISPLAY INVISIBLE (-9050 1550);
FORCEPROP 1 LAST OFFPAGE TRUE
J 0
(-8725 1425);
DISPLAY 0.872340 (-8725 1425);
PAINT GREEN (-8725 1425);
DISPLAY INVISIBLE (-8725 1425);
FORCEPROP 1 LAST COMMENT_BODY TRUE
J 0
(-8925 1450);
DISPLAY 0.872340 (-8925 1450);
PAINT GREEN (-8925 1450);
DISPLAY INVISIBLE (-8925 1450);
FORCEPROP 2 LAST PATH I2
J 0
(-9300 1600);
DISPLAY 0.680851 (-9300 1600);
DISPLAY INVISIBLE (-9300 1600);
FORCEADD Q_RES..2
(-8900 4425);
FORCEPROP 1 LAST LOCATION R2843
J 0
(-8855 4550);
DISPLAY 0.638298 (-8855 4550);
FORCEPROP 0 LAST $SEC 1
J 0
(-8850 4600);
DISPLAY 0.680851 (-8850 4600);
PAINT MONO (-8850 4600);
DISPLAY INVISIBLE (-8850 4600);
FORCEPROP 0 LAST CDS_SEC 1
J 0
(-8850 4600);
DISPLAY 1.021277 (-8850 4600);
DISPLAY INVISIBLE (-8850 4600);
FORCEPROP 1 LASTPIN (-8900 4525) $PN 1
J 0
(-8895 4487);
DISPLAY 0.787234 (-8895 4487);
PAINT MONO (-8895 4487);
FORCEPROP 1 LASTPIN (-8900 4325) $PN 2
J 0
(-8895 4335);
DISPLAY 0.787234 (-8895 4335);
PAINT MONO (-8895 4335);
FORCEPROP 1 LAST PACK_TYPE 0402LF
J 0
(-8860 4250);
DISPLAY 0.510638 (-8860 4250);
FORCEPROP 1 LAST WATTAGE 1/16W
J 0
(-8860 4400);
DISPLAY 0.510638 (-8860 4400);
FORCEPROP 1 LAST MATERIAL CHIP
J 0
(-8860 4350);
DISPLAY 0.510638 (-8860 4350);
FORCEPROP 1 LAST TOLERANCE 1%
J 0
(-8855 4450);
DISPLAY 0.510638 (-8855 4450);
FORCEPROP 1 LAST VALUE 4.7K
J 0
(-8855 4500);
DISPLAY 0.510638 (-8855 4500);
FORCEPROP 2 LAST CDS_LIB pure_quanta
J 0
(-8900 4425);
DISPLAY INVISIBLE (-8900 4425);
FORCEPROP 1 LAST PATH I20
J 0
(-8850 4600);
DISPLAY 0.978723 (-8850 4600);
PAINT WHITE (-8850 4600);
DISPLAY INVISIBLE (-8850 4600);
FORCEPROP 1 LAST PART_NUMBER CS24702FB06
J 0
(-8860 4300);
DISPLAY 0.510638 (-8860 4300);
DISPLAY INVISIBLE (-8860 4300);
FORCEADD Q_RES..2
(-8900 4900);
FORCEPROP 1 LAST LOCATION R2908
J 0
(-8855 5025);
DISPLAY 0.510638 (-8855 5025);
FORCEPROP 2 LAST $SEC 1
J 0
(-8850 5125);
DISPLAY 0.680851 (-8850 5125);
PAINT MONO (-8850 5125);
DISPLAY INVISIBLE (-8850 5125);
FORCEPROP 2 LAST CDS_SEC 1
J 0
(-8850 5125);
DISPLAY 1.021277 (-8850 5125);
DISPLAY INVISIBLE (-8850 5125);
FORCEPROP 1 LASTPIN (-8900 5000) $PN 1
J 0
(-8895 4962);
DISPLAY 0.787234 (-8895 4962);
PAINT MONO (-8895 4962);
FORCEPROP 1 LASTPIN (-8900 4800) $PN 2
J 0
(-8895 4810);
DISPLAY 0.787234 (-8895 4810);
PAINT MONO (-8895 4810);
FORCEPROP 1 LAST PACK_TYPE 0402LF
J 0
(-8860 4725);
DISPLAY 0.510638 (-8860 4725);
FORCEPROP 1 LAST TOLERANCE 1%
J 0
(-8855 4925);
DISPLAY 0.510638 (-8855 4925);
FORCEPROP 1 LAST WATTAGE 1/16W
J 0
(-8860 4875);
DISPLAY 0.510638 (-8860 4875);
FORCEPROP 1 LAST VALUE 5.11K
J 0
(-8855 4975);
DISPLAY 0.510638 (-8855 4975);
FORCEPROP 1 LAST MATERIAL CHIP
J 0
(-8860 4825);
DISPLAY 0.510638 (-8860 4825);
FORCEPROP 2 LAST CDS_LIB pure_quanta
J 0
(-8900 4900);
DISPLAY INVISIBLE (-8900 4900);
FORCEPROP 1 LAST PATH I21
J 0
(-8850 5075);
DISPLAY 0.978723 (-8850 5075);
PAINT WHITE (-8850 5075);
DISPLAY INVISIBLE (-8850 5075);
FORCEPROP 1 LAST PART_NUMBER CS25112FB04
J 0
(-8860 4775);
DISPLAY 0.510638 (-8860 4775);
DISPLAY INVISIBLE (-8860 4775);
FORCEADD Q_RES..1
(-8275 4500);
FORCEPROP 1 LAST LOCATION R3684
J 0
(-8475 4500);
DISPLAY 0.510638 (-8475 4500);
FORCEPROP 0 LAST $SEC 1
J 0
(-8400 4550);
DISPLAY 0.680851 (-8400 4550);
PAINT MONO (-8400 4550);
DISPLAY INVISIBLE (-8400 4550);
FORCEPROP 0 LAST CDS_SEC 1
J 0
(-8400 4550);
DISPLAY 1.021277 (-8400 4550);
DISPLAY INVISIBLE (-8400 4550);
FORCEPROP 1 LASTPIN (-8375 4500) $PN 1
J 0
(-8363 4512);
DISPLAY 0.787234 (-8363 4512);
PAINT MONO (-8363 4512);
FORCEPROP 1 LASTPIN (-8175 4500) $PN 2
J 0
(-8213 4512);
DISPLAY 0.787234 (-8213 4512);
PAINT MONO (-8213 4512);
FORCEPROP 1 LAST MATERIAL CHIP
J 0
(-8050 4500);
DISPLAY 0.404255 (-8050 4500);
PAINT RED (-8050 4500);
FORCEPROP 1 LAST VALUE 0
J 2
(-8125 4500);
DISPLAY 0.404255 (-8125 4500);
FORCEPROP 1 LAST TOLERANCE 5%
J 0
(-8100 4500);
DISPLAY 0.404255 (-8100 4500);
FORCEPROP 0 LAST ROOM ADC_TI_BOM1
J 0
(-8425 4450);
DISPLAY 0.553191 (-8425 4450);
PAINT RED (-8425 4450);
FORCEPROP 1 LAST PACK_TYPE 0402LF
J 0
(-8025 4500);
DISPLAY 0.510638 (-8025 4500);
DISPLAY INVISIBLE (-8025 4500);
FORCEPROP 1 LAST WATTAGE 1/16W
J 2
(-8175 4425);
DISPLAY 0.319149 (-8175 4425);
DISPLAY INVISIBLE (-8175 4425);
FORCEPROP 2 LAST CDS_LIB pure_quanta
J 0
(-8275 4500);
DISPLAY INVISIBLE (-8275 4500);
FORCEPROP 1 LAST PATH I22
J 0
(-8325 4650);
DISPLAY 0.978723 (-8325 4650);
PAINT WHITE (-8325 4650);
DISPLAY INVISIBLE (-8325 4650);
FORCEPROP 1 LAST PART_NUMBER CS00002JB13
J 0
(-8350 4450);
DISPLAY 0.319149 (-8350 4450);
DISPLAY INVISIBLE (-8350 4450);
FORCEADD Q_RES..1
(-8275 4650);
FORCEPROP 1 LAST LOCATION R3683
J 0
(-8475 4650);
DISPLAY 0.510638 (-8475 4650);
FORCEPROP 0 LAST $SEC 1
J 0
(-8400 4700);
DISPLAY 0.680851 (-8400 4700);
PAINT MONO (-8400 4700);
DISPLAY INVISIBLE (-8400 4700);
FORCEPROP 0 LAST CDS_SEC 1
J 0
(-8400 4700);
DISPLAY 1.021277 (-8400 4700);
DISPLAY INVISIBLE (-8400 4700);
FORCEPROP 1 LASTPIN (-8375 4650) $PN 1
J 0
(-8363 4662);
DISPLAY 0.787234 (-8363 4662);
PAINT MONO (-8363 4662);
FORCEPROP 1 LASTPIN (-8175 4650) $PN 2
J 0
(-8213 4662);
DISPLAY 0.787234 (-8213 4662);
PAINT MONO (-8213 4662);
FORCEPROP 1 LAST MATERIAL EMPTY
J 0
(-8050 4650);
DISPLAY 0.404255 (-8050 4650);
FORCEPROP 1 LAST TOLERANCE 5%
J 0
(-8100 4650);
DISPLAY 0.404255 (-8100 4650);
FORCEPROP 1 LAST VALUE 0
J 2
(-8125 4650);
DISPLAY 0.404255 (-8125 4650);
FORCEPROP 0 LAST ROOM ADC_MAM_BOM2
J 0
(-8425 4775);
DISPLAY 0.553191 (-8425 4775);
PAINT RED (-8425 4775);
FORCEPROP 1 LAST PACK_TYPE 0402LF
J 0
(-8025 4650);
DISPLAY 0.510638 (-8025 4650);
DISPLAY INVISIBLE (-8025 4650);
FORCEPROP 1 LAST WATTAGE 1/16W
J 2
(-8175 4575);
DISPLAY 0.319149 (-8175 4575);
DISPLAY INVISIBLE (-8175 4575);
FORCEPROP 2 LAST CDS_LIB pure_quanta
J 0
(-8275 4650);
DISPLAY INVISIBLE (-8275 4650);
FORCEPROP 1 LAST PATH I23
J 0
(-8325 4800);
DISPLAY 0.978723 (-8325 4800);
PAINT WHITE (-8325 4800);
DISPLAY INVISIBLE (-8325 4800);
FORCEPROP 1 LAST PART_NUMBER CS00002JB13
J 0
(-8350 4600);
DISPLAY 0.319149 (-8350 4600);
DISPLAY INVISIBLE (-8350 4600);
FORCEADD UNIVERSAL_GND..1
(-8900 5350);
FORCEPROP 3 LASTPIN (-8900 5400) SIG_NAME GND\g
J 0
(-8890 5410);
DISPLAY 0.659574 (-8890 5410);
PAINT MONO (-8890 5410);
DISPLAY INVISIBLE (-8890 5410);
FORCEPROP 2 LAST CDS_LIB pure_quanta_power
J 0
(-8900 5350);
DISPLAY INVISIBLE (-8900 5350);
FORCEPROP 1 LAST HDL_POWER GND
J 1
(-8875 5275);
DISPLAY 0.872340 (-8875 5275);
PAINT GREEN (-8875 5275);
DISPLAY INVISIBLE (-8875 5275);
FORCEPROP 1 LAST PATH I24
J 0
(-8825 5350);
DISPLAY 0.872340 (-8825 5350);
PAINT AQUA (-8825 5350);
DISPLAY INVISIBLE (-8825 5350);
FORCEADD UNIVERSAL_POWER..1
(-8900 5150);
FORCEPROP 3 LASTPIN (-8900 5100) SIG_NAME P3V3\g
J 0
(-8890 5110);
DISPLAY 0.659574 (-8890 5110);
PAINT MONO (-8890 5110);
DISPLAY INVISIBLE (-8890 5110);
FORCEPROP 1 LAST HDL_POWER P3V3
J 1
(-8900 5200);
DISPLAY 0.872340 (-8900 5200);
PAINT GREEN (-8900 5200);
FORCEPROP 2 LAST CDS_LIB pure_quanta_power
J 0
(-8900 5150);
DISPLAY INVISIBLE (-8900 5150);
FORCEPROP 1 LAST PATH I25
J 0
(-8850 5175);
DISPLAY 0.872340 (-8850 5175);
PAINT AQUA (-8850 5175);
DISPLAY INVISIBLE (-8850 5175);
FORCEADD Q_RES..2
(-8900 5700);
FORCEPROP 1 LAST LOCATION R1785
J 0
(-8855 5825);
DISPLAY 0.638298 (-8855 5825);
FORCEPROP 0 LAST $SEC 1
J 0
(-8850 5875);
DISPLAY 0.680851 (-8850 5875);
PAINT MONO (-8850 5875);
DISPLAY INVISIBLE (-8850 5875);
FORCEPROP 0 LAST CDS_SEC 1
J 0
(-8850 5875);
DISPLAY 1.021277 (-8850 5875);
DISPLAY INVISIBLE (-8850 5875);
FORCEPROP 1 LASTPIN (-8900 5800) $PN 1
J 0
(-8895 5762);
DISPLAY 0.787234 (-8895 5762);
PAINT MONO (-8895 5762);
FORCEPROP 1 LASTPIN (-8900 5600) $PN 2
J 0
(-8895 5610);
DISPLAY 0.787234 (-8895 5610);
PAINT MONO (-8895 5610);
FORCEPROP 1 LAST WATTAGE 1/16W
J 0
(-8860 5675);
DISPLAY 0.510638 (-8860 5675);
FORCEPROP 1 LAST PACK_TYPE 0402LF
J 0
(-8860 5525);
DISPLAY 0.510638 (-8860 5525);
FORCEPROP 1 LAST TOLERANCE 1%
J 0
(-8855 5725);
DISPLAY 0.510638 (-8855 5725);
FORCEPROP 1 LAST VALUE 4.7K
J 0
(-8855 5775);
DISPLAY 0.510638 (-8855 5775);
FORCEPROP 1 LAST MATERIAL CHIP
J 0
(-8860 5625);
DISPLAY 0.510638 (-8860 5625);
FORCEPROP 2 LAST CDS_LIB pure_quanta
J 0
(-8900 5700);
DISPLAY INVISIBLE (-8900 5700);
FORCEPROP 1 LAST PATH I26
J 0
(-8850 5875);
DISPLAY 0.978723 (-8850 5875);
PAINT WHITE (-8850 5875);
DISPLAY INVISIBLE (-8850 5875);
FORCEPROP 1 LAST PART_NUMBER CS24702FB06
J 0
(-8860 5575);
DISPLAY 0.510638 (-8860 5575);
DISPLAY INVISIBLE (-8860 5575);
FORCEADD Q_RES..1
(-8200 5825);
FORCEPROP 1 LAST LOCATION R3682
J 0
(-8400 5825);
DISPLAY 0.510638 (-8400 5825);
FORCEPROP 0 LAST $SEC 1
J 0
(-8325 5875);
DISPLAY 0.680851 (-8325 5875);
PAINT MONO (-8325 5875);
DISPLAY INVISIBLE (-8325 5875);
FORCEPROP 0 LAST CDS_SEC 1
J 0
(-8325 5875);
DISPLAY 1.021277 (-8325 5875);
DISPLAY INVISIBLE (-8325 5875);
FORCEPROP 1 LASTPIN (-8300 5825) $PN 1
J 0
(-8288 5837);
DISPLAY 0.787234 (-8288 5837);
PAINT MONO (-8288 5837);
FORCEPROP 1 LASTPIN (-8100 5825) $PN 2
J 0
(-8138 5837);
DISPLAY 0.787234 (-8138 5837);
PAINT MONO (-8138 5837);
FORCEPROP 1 LAST MATERIAL CHIP
J 0
(-7975 5825);
DISPLAY 0.404255 (-7975 5825);
PAINT RED (-7975 5825);
FORCEPROP 1 LAST TOLERANCE 5%
J 0
(-8025 5825);
DISPLAY 0.404255 (-8025 5825);
FORCEPROP 1 LAST VALUE 0
J 2
(-8050 5825);
DISPLAY 0.404255 (-8050 5825);
FORCEPROP 0 LAST ROOM ADC_TI_BOM1
J 0
(-8350 5775);
DISPLAY 0.553191 (-8350 5775);
PAINT RED (-8350 5775);
FORCEPROP 2 LAST CDS_LIB pure_quanta
J 0
(-8200 5825);
DISPLAY INVISIBLE (-8200 5825);
FORCEPROP 1 LAST WATTAGE 1/16W
J 2
(-8100 5750);
DISPLAY 0.319149 (-8100 5750);
DISPLAY INVISIBLE (-8100 5750);
FORCEPROP 1 LAST PACK_TYPE 0402LF
J 0
(-7950 5825);
DISPLAY 0.510638 (-7950 5825);
DISPLAY INVISIBLE (-7950 5825);
FORCEPROP 1 LAST PATH I27
J 0
(-8250 5975);
DISPLAY 0.978723 (-8250 5975);
PAINT WHITE (-8250 5975);
DISPLAY INVISIBLE (-8250 5975);
FORCEPROP 1 LAST PART_NUMBER CS00002JB13
J 0
(-8275 5775);
DISPLAY 0.319149 (-8275 5775);
DISPLAY INVISIBLE (-8275 5775);
FORCEADD Q_RES..2
(-8900 6225);
FORCEPROP 1 LAST LOCATION R2907
J 0
(-8855 6350);
DISPLAY 0.510638 (-8855 6350);
FORCEPROP 2 LAST $SEC 1
J 0
(-8850 6450);
DISPLAY 0.680851 (-8850 6450);
PAINT MONO (-8850 6450);
DISPLAY INVISIBLE (-8850 6450);
FORCEPROP 2 LAST CDS_SEC 1
J 0
(-8850 6450);
DISPLAY 1.021277 (-8850 6450);
DISPLAY INVISIBLE (-8850 6450);
FORCEPROP 1 LASTPIN (-8900 6325) $PN 1
J 0
(-8895 6287);
DISPLAY 0.787234 (-8895 6287);
PAINT MONO (-8895 6287);
FORCEPROP 1 LASTPIN (-8900 6125) $PN 2
J 0
(-8895 6135);
DISPLAY 0.787234 (-8895 6135);
PAINT MONO (-8895 6135);
FORCEPROP 1 LAST PACK_TYPE 0402LF
J 0
(-8860 6050);
DISPLAY 0.510638 (-8860 6050);
FORCEPROP 1 LAST MATERIAL CHIP
J 0
(-8860 6150);
DISPLAY 0.510638 (-8860 6150);
FORCEPROP 1 LAST VALUE 5.11K
J 0
(-8855 6300);
DISPLAY 0.510638 (-8855 6300);
FORCEPROP 1 LAST TOLERANCE 1%
J 0
(-8855 6250);
DISPLAY 0.510638 (-8855 6250);
FORCEPROP 1 LAST WATTAGE 1/16W
J 0
(-8860 6200);
DISPLAY 0.510638 (-8860 6200);
FORCEPROP 2 LAST CDS_LIB pure_quanta
J 0
(-8900 6225);
DISPLAY INVISIBLE (-8900 6225);
FORCEPROP 1 LAST PATH I28
J 0
(-8850 6400);
DISPLAY 0.978723 (-8850 6400);
PAINT WHITE (-8850 6400);
DISPLAY INVISIBLE (-8850 6400);
FORCEPROP 1 LAST PART_NUMBER CS25112FB04
J 0
(-8860 6100);
DISPLAY 0.510638 (-8860 6100);
DISPLAY INVISIBLE (-8860 6100);
FORCEADD UNIVERSAL_POWER..1
(-8900 6475);
FORCEPROP 3 LASTPIN (-8900 6425) SIG_NAME P3V3_AUX\g
J 0
(-8890 6435);
DISPLAY 0.659574 (-8890 6435);
PAINT MONO (-8890 6435);
DISPLAY INVISIBLE (-8890 6435);
FORCEPROP 1 LAST HDL_POWER P3V3_AUX
J 1
(-8900 6525);
DISPLAY 0.872340 (-8900 6525);
PAINT GREEN (-8900 6525);
FORCEPROP 2 LAST CDS_LIB pure_quanta_power
J 0
(-8900 6475);
DISPLAY INVISIBLE (-8900 6475);
FORCEPROP 1 LAST PATH I29
J 0
(-8850 6500);
DISPLAY 0.872340 (-8850 6500);
PAINT AQUA (-8850 6500);
DISPLAY INVISIBLE (-8850 6500);
FORCEADD UNIVERSAL_GND..1
(-8925 1700);
FORCEPROP 3 LASTPIN (-8925 1750) SIG_NAME GND\g
J 0
(-8915 1760);
DISPLAY 0.659574 (-8915 1760);
PAINT MONO (-8915 1760);
DISPLAY INVISIBLE (-8915 1760);
FORCEPROP 2 LAST CDS_LIB pure_quanta_power
J 0
(-8925 1700);
DISPLAY INVISIBLE (-8925 1700);
FORCEPROP 1 LAST HDL_POWER GND
J 1
(-8900 1625);
DISPLAY 0.872340 (-8900 1625);
PAINT GREEN (-8900 1625);
DISPLAY INVISIBLE (-8900 1625);
FORCEPROP 1 LAST PATH I3
J 0
(-8850 1700);
DISPLAY 0.872340 (-8850 1700);
PAINT AQUA (-8850 1700);
DISPLAY INVISIBLE (-8850 1700);
FORCEADD Q_RES..1
(-8200 5975);
FORCEPROP 1 LAST LOCATION R3681
J 0
(-8400 5975);
DISPLAY 0.510638 (-8400 5975);
FORCEPROP 0 LAST $SEC 1
J 0
(-8325 6025);
DISPLAY 0.680851 (-8325 6025);
PAINT MONO (-8325 6025);
DISPLAY INVISIBLE (-8325 6025);
FORCEPROP 0 LAST CDS_SEC 1
J 0
(-8325 6025);
DISPLAY 1.021277 (-8325 6025);
DISPLAY INVISIBLE (-8325 6025);
FORCEPROP 1 LASTPIN (-8300 5975) $PN 1
J 0
(-8288 5987);
DISPLAY 0.787234 (-8288 5987);
PAINT MONO (-8288 5987);
FORCEPROP 1 LASTPIN (-8100 5975) $PN 2
J 0
(-8138 5987);
DISPLAY 0.787234 (-8138 5987);
PAINT MONO (-8138 5987);
FORCEPROP 0 LAST ROOM ADC_MAM_BOM2
J 0
(-8350 6075);
DISPLAY 0.553191 (-8350 6075);
PAINT RED (-8350 6075);
FORCEPROP 1 LAST MATERIAL EMPTY
J 0
(-7975 5975);
DISPLAY 0.404255 (-7975 5975);
FORCEPROP 1 LAST VALUE 0
J 2
(-8050 5975);
DISPLAY 0.404255 (-8050 5975);
FORCEPROP 1 LAST TOLERANCE 5%
J 0
(-8025 5975);
DISPLAY 0.404255 (-8025 5975);
FORCEPROP 2 LAST CDS_LIB pure_quanta
J 0
(-8200 5975);
DISPLAY INVISIBLE (-8200 5975);
FORCEPROP 1 LAST WATTAGE 1/16W
J 2
(-8100 5900);
DISPLAY 0.319149 (-8100 5900);
DISPLAY INVISIBLE (-8100 5900);
FORCEPROP 1 LAST PACK_TYPE 0402LF
J 0
(-7950 5975);
DISPLAY 0.510638 (-7950 5975);
DISPLAY INVISIBLE (-7950 5975);
FORCEPROP 1 LAST PATH I30
J 0
(-8250 6125);
DISPLAY 0.978723 (-8250 6125);
PAINT WHITE (-8250 6125);
DISPLAY INVISIBLE (-8250 6125);
FORCEPROP 1 LAST PART_NUMBER CS00002JB13
J 0
(-8275 5925);
DISPLAY 0.319149 (-8275 5925);
DISPLAY INVISIBLE (-8275 5925);
FORCEADD UNIVERSAL_GND..1
(-7900 3950);
FORCEPROP 3 LASTPIN (-7900 4000) SIG_NAME GND\g
J 0
(-7890 4010);
DISPLAY 0.659574 (-7890 4010);
PAINT MONO (-7890 4010);
DISPLAY INVISIBLE (-7890 4010);
FORCEPROP 2 LAST CDS_LIB pure_quanta_power
J 0
(-7900 3950);
DISPLAY INVISIBLE (-7900 3950);
FORCEPROP 1 LAST HDL_POWER GND
J 1
(-7875 3875);
DISPLAY 0.872340 (-7875 3875);
PAINT GREEN (-7875 3875);
DISPLAY INVISIBLE (-7875 3875);
FORCEPROP 1 LAST PATH I31
J 0
(-7825 3950);
DISPLAY 0.872340 (-7825 3950);
PAINT AQUA (-7825 3950);
DISPLAY INVISIBLE (-7825 3950);
FORCEADD Q_CAP..1
R 2
(-7900 4225);
FORCEPROP 1 LAST LOCATION C2048
J 2
(-7700 4350);
DISPLAY 0.638298 (-7700 4350);
FORCEPROP 0 LAST $SEC 1
J 0
(-7800 4375);
DISPLAY 0.680851 (-7800 4375);
PAINT MONO (-7800 4375);
DISPLAY INVISIBLE (-7800 4375);
FORCEPROP 0 LAST CDS_SEC 1
J 0
(-7800 4375);
DISPLAY 1.021277 (-7800 4375);
DISPLAY INVISIBLE (-7800 4375);
FORCEPROP 1 LASTPIN (-7900 4325) $PN 1
J 2
(-7910 4305);
DISPLAY 0.787234 (-7910 4305);
PAINT MONO (-7910 4305);
FORCEPROP 1 LASTPIN (-7900 4125) $PN 2
J 2
(-7910 4105);
DISPLAY 0.787234 (-7910 4105);
PAINT MONO (-7910 4105);
FORCEPROP 1 LAST VOLTAGE 25V
J 2
(-7750 4250);
DISPLAY 0.510638 (-7750 4250);
FORCEPROP 1 LAST MATERIAL X7R
J 2
(-7750 4150);
DISPLAY 0.510638 (-7750 4150);
PAINT RED (-7750 4150);
FORCEPROP 0 LAST ROOM ADC_TI_BOM1
J 0
(-7850 4000);
DISPLAY 0.446809 (-7850 4000);
PAINT RED (-7850 4000);
FORCEPROP 1 LAST PACK_TYPE 0402
J 2
(-7725 4050);
DISPLAY 0.510638 (-7725 4050);
FORCEPROP 1 LAST TOLERANCE 10%
J 2
(-7750 4200);
DISPLAY 0.510638 (-7750 4200);
FORCEPROP 1 LAST VALUE 0.1UF
J 2
(-7725 4300);
DISPLAY 0.510638 (-7725 4300);
FORCEPROP 2 LAST CDS_LIB pure_quanta
J 0
(-7900 4225);
DISPLAY INVISIBLE (-7900 4225);
FORCEPROP 1 LAST PATH I32
J 2
(-7950 4375);
DISPLAY 0.978723 (-7950 4375);
PAINT WHITE (-7950 4375);
DISPLAY INVISIBLE (-7950 4375);
FORCEPROP 1 LAST PART_NUMBER CH4104K1B00
J 2
(-7600 4100);
DISPLAY 0.510638 (-7600 4100);
DISPLAY INVISIBLE (-7600 4100);
FORCEADD UNIVERSAL_GND..1
(-6875 625);
FORCEPROP 3 LASTPIN (-6875 675) SIG_NAME GND\g
J 0
(-6865 685);
DISPLAY 0.659574 (-6865 685);
PAINT MONO (-6865 685);
DISPLAY INVISIBLE (-6865 685);
FORCEPROP 2 LAST CDS_LIB pure_quanta_power
J 0
(-6875 625);
DISPLAY INVISIBLE (-6875 625);
FORCEPROP 1 LAST HDL_POWER GND
J 1
(-6850 550);
DISPLAY 0.872340 (-6850 550);
PAINT GREEN (-6850 550);
DISPLAY INVISIBLE (-6850 550);
FORCEPROP 1 LAST PATH I33
J 0
(-6800 625);
DISPLAY 0.872340 (-6800 625);
PAINT AQUA (-6800 625);
DISPLAY INVISIBLE (-6800 625);
FORCEADD Q_CAP..1
R 2
(-6875 875);
FORCEPROP 1 LAST LOCATION C2050
J 2
(-6725 1000);
DISPLAY 0.638298 (-6725 1000);
FORCEPROP 0 LAST $SEC 1
J 0
(-6775 1025);
DISPLAY 0.680851 (-6775 1025);
PAINT MONO (-6775 1025);
DISPLAY INVISIBLE (-6775 1025);
FORCEPROP 0 LAST CDS_SEC 1
J 0
(-6775 1025);
DISPLAY 1.021277 (-6775 1025);
DISPLAY INVISIBLE (-6775 1025);
FORCEPROP 1 LASTPIN (-6875 975) $PN 1
J 2
(-6885 955);
DISPLAY 0.787234 (-6885 955);
PAINT MONO (-6885 955);
FORCEPROP 1 LASTPIN (-6875 775) $PN 2
J 2
(-6885 755);
DISPLAY 0.787234 (-6885 755);
PAINT MONO (-6885 755);
FORCEPROP 1 LAST VALUE 0.1UF
J 2
(-6700 950);
DISPLAY 0.510638 (-6700 950);
FORCEPROP 1 LAST PACK_TYPE 0402
J 2
(-6700 700);
DISPLAY 0.510638 (-6700 700);
FORCEPROP 1 LAST TOLERANCE 10%
J 2
(-6725 850);
DISPLAY 0.510638 (-6725 850);
FORCEPROP 1 LAST VOLTAGE 25V
J 2
(-6725 900);
DISPLAY 0.510638 (-6725 900);
FORCEPROP 1 LAST MATERIAL X7R
J 2
(-6725 800);
DISPLAY 0.510638 (-6725 800);
FORCEPROP 0 LAST ROOM ADC_TI_BOM1
J 0
(-6850 650);
DISPLAY 0.553191 (-6850 650);
PAINT RED (-6850 650);
FORCEPROP 2 LAST CDS_LIB pure_quanta
J 0
(-6875 875);
DISPLAY INVISIBLE (-6875 875);
FORCEPROP 1 LAST PATH I34
J 2
(-6925 1025);
DISPLAY 0.978723 (-6925 1025);
PAINT WHITE (-6925 1025);
DISPLAY INVISIBLE (-6925 1025);
FORCEPROP 1 LAST PART_NUMBER CH4104K1B00
J 2
(-6575 750);
DISPLAY 0.510638 (-6575 750);
DISPLAY INVISIBLE (-6575 750);
FORCEADD UNIVERSAL_GND..1
(-6525 600);
FORCEPROP 3 LASTPIN (-6525 650) SIG_NAME GND\g
J 0
(-6515 660);
DISPLAY 0.659574 (-6515 660);
PAINT MONO (-6515 660);
DISPLAY INVISIBLE (-6515 660);
FORCEPROP 2 LAST CDS_LIB pure_quanta_power
J 0
(-6525 600);
DISPLAY INVISIBLE (-6525 600);
FORCEPROP 1 LAST HDL_POWER GND
J 1
(-6500 525);
DISPLAY 0.872340 (-6500 525);
PAINT GREEN (-6500 525);
DISPLAY INVISIBLE (-6500 525);
FORCEPROP 1 LAST PATH I35
J 0
(-6450 600);
DISPLAY 0.872340 (-6450 600);
PAINT AQUA (-6450 600);
DISPLAY INVISIBLE (-6450 600);
FORCEADD Q_CAP..1
(-6525 875);
FORCEPROP 1 LAST LOCATION C2045
J 0
(-6475 975);
DISPLAY 0.510638 (-6475 975);
FORCEPROP 2 LAST $SEC 1
J 0
(-6475 1075);
DISPLAY 0.680851 (-6475 1075);
PAINT MONO (-6475 1075);
DISPLAY INVISIBLE (-6475 1075);
FORCEPROP 0 LAST CDS_SEC 1
J 0
(-6475 1050);
DISPLAY 1.021277 (-6475 1050);
DISPLAY INVISIBLE (-6475 1050);
FORCEPROP 1 LASTPIN (-6525 975) $PN 1
J 0
(-6515 955);
DISPLAY 0.787234 (-6515 955);
PAINT MONO (-6515 955);
FORCEPROP 1 LASTPIN (-6525 775) $PN 2
J 0
(-6515 755);
DISPLAY 0.787234 (-6515 755);
PAINT MONO (-6515 755);
FORCEPROP 0 LAST ROOM ADC_MAM_BOM2
J 0
(-6475 625);
DISPLAY 0.553191 (-6475 625);
PAINT RED (-6475 625);
FORCEPROP 1 LAST MATERIAL EMPTY
J 0
(-6475 775);
DISPLAY 0.510638 (-6475 775);
FORCEPROP 1 LAST PACK_TYPE 0402
J 0
(-6475 675);
DISPLAY 0.510638 (-6475 675);
FORCEPROP 1 LAST TOLERANCE 5%
J 0
(-6475 825);
DISPLAY 0.510638 (-6475 825);
FORCEPROP 1 LAST VOLTAGE 50V
J 0
(-6475 875);
DISPLAY 0.510638 (-6475 875);
FORCEPROP 1 LAST VALUE 100PF
J 0
(-6475 925);
DISPLAY 0.510638 (-6475 925);
FORCEPROP 2 LAST CDS_LIB pure_quanta
J 0
(-6525 875);
DISPLAY INVISIBLE (-6525 875);
FORCEPROP 1 LAST PATH I36
J 0
(-6475 1025);
DISPLAY 0.978723 (-6475 1025);
PAINT WHITE (-6475 1025);
DISPLAY INVISIBLE (-6475 1025);
FORCEPROP 1 LAST PART_NUMBER CH11006JB18
J 0
(-6475 725);
DISPLAY 0.510638 (-6475 725);
DISPLAY INVISIBLE (-6475 725);
FORCEADD UNIVERSAL_GND..1
(-4550 500);
FORCEPROP 3 LASTPIN (-4550 550) SIG_NAME GND\g
J 0
(-4540 560);
DISPLAY 0.659574 (-4540 560);
PAINT MONO (-4540 560);
DISPLAY INVISIBLE (-4540 560);
FORCEPROP 2 LAST CDS_LIB pure_quanta_power
J 0
(-4550 500);
PAINT MONO (-4550 500);
DISPLAY INVISIBLE (-4550 500);
FORCEPROP 1 LAST HDL_POWER GND
J 1
(-4525 425);
DISPLAY 0.872340 (-4525 425);
PAINT GREEN (-4525 425);
DISPLAY INVISIBLE (-4525 425);
FORCEPROP 1 LAST PATH I37
J 0
(-4475 500);
DISPLAY 0.872340 (-4475 500);
PAINT AQUA (-4475 500);
DISPLAY INVISIBLE (-4475 500);
FORCEADD Q_RES..2
(-4550 725);
FORCEPROP 1 LAST LOCATION R3668
J 0
(-4505 850);
DISPLAY 0.638298 (-4505 850);
FORCEPROP 0 LAST $SEC 1
J 0
(-4500 900);
DISPLAY 0.680851 (-4500 900);
PAINT MONO (-4500 900);
DISPLAY INVISIBLE (-4500 900);
FORCEPROP 0 LAST CDS_SEC 1
J 0
(-4500 900);
DISPLAY 1.021277 (-4500 900);
DISPLAY INVISIBLE (-4500 900);
FORCEPROP 1 LASTPIN (-4550 825) $PN 1
J 0
(-4545 787);
DISPLAY 0.787234 (-4545 787);
PAINT MONO (-4545 787);
FORCEPROP 1 LASTPIN (-4550 625) $PN 2
J 0
(-4545 635);
DISPLAY 0.787234 (-4545 635);
PAINT MONO (-4545 635);
FORCEPROP 0 LAST ROOM ADC_TI_BOM1
J 0
(-4600 900);
DISPLAY 0.446809 (-4600 900);
PAINT RED (-4600 900);
FORCEPROP 1 LAST WATTAGE 1/16W
J 0
(-4510 700);
DISPLAY 0.638298 (-4510 700);
FORCEPROP 1 LAST MATERIAL CHIP
J 0
(-4510 650);
DISPLAY 0.638298 (-4510 650);
FORCEPROP 1 LAST TOLERANCE 1%
J 0
(-4505 750);
DISPLAY 0.638298 (-4505 750);
FORCEPROP 1 LAST VALUE 1K
J 0
(-4505 800);
DISPLAY 0.638298 (-4505 800);
FORCEPROP 1 LAST PACK_TYPE 0402LF
J 0
(-4510 600);
DISPLAY 0.638298 (-4510 600);
FORCEPROP 2 LAST CDS_LIB pure_quanta
J 0
(-4550 725);
DISPLAY INVISIBLE (-4550 725);
FORCEPROP 1 LAST PATH I38
J 0
(-4500 900);
DISPLAY 0.978723 (-4500 900);
PAINT WHITE (-4500 900);
DISPLAY INVISIBLE (-4500 900);
FORCEPROP 1 LAST PART_NUMBER CS21002FB06
J 0
(-4510 550);
DISPLAY 0.638298 (-4510 550);
DISPLAY INVISIBLE (-4510 550);
FORCEADD UNIVERSAL_GND..1
(-4300 500);
FORCEPROP 3 LASTPIN (-4300 550) SIG_NAME GND\g
J 0
(-4290 560);
DISPLAY 0.659574 (-4290 560);
PAINT MONO (-4290 560);
DISPLAY INVISIBLE (-4290 560);
FORCEPROP 2 LAST CDS_LIB pure_quanta_power
J 0
(-4300 500);
PAINT MONO (-4300 500);
DISPLAY INVISIBLE (-4300 500);
FORCEPROP 1 LAST HDL_POWER GND
J 1
(-4275 425);
DISPLAY 0.872340 (-4275 425);
PAINT GREEN (-4275 425);
DISPLAY INVISIBLE (-4275 425);
FORCEPROP 1 LAST PATH I39
J 0
(-4225 500);
DISPLAY 0.872340 (-4225 500);
PAINT AQUA (-4225 500);
DISPLAY INVISIBLE (-4225 500);
FORCEADD Q_RES..2
(-4300 725);
FORCEPROP 1 LAST LOCATION R3670
J 0
(-4255 850);
DISPLAY 0.638298 (-4255 850);
FORCEPROP 0 LAST $SEC 1
J 0
(-4250 900);
DISPLAY 0.680851 (-4250 900);
PAINT MONO (-4250 900);
DISPLAY INVISIBLE (-4250 900);
FORCEPROP 0 LAST CDS_SEC 1
J 0
(-4250 900);
DISPLAY 1.021277 (-4250 900);
DISPLAY INVISIBLE (-4250 900);
FORCEPROP 1 LASTPIN (-4300 825) $PN 1
J 0
(-4295 787);
DISPLAY 0.787234 (-4295 787);
PAINT MONO (-4295 787);
FORCEPROP 1 LASTPIN (-4300 625) $PN 2
J 0
(-4295 635);
DISPLAY 0.787234 (-4295 635);
PAINT MONO (-4295 635);
FORCEPROP 0 LAST ROOM ADC_TI_BOM1
J 0
(-4250 900);
DISPLAY 0.553191 (-4250 900);
PAINT RED (-4250 900);
FORCEPROP 1 LAST VALUE 1K
J 0
(-4255 800);
DISPLAY 0.638298 (-4255 800);
FORCEPROP 1 LAST TOLERANCE 1%
J 0
(-4255 750);
DISPLAY 0.638298 (-4255 750);
FORCEPROP 1 LAST PACK_TYPE 0402LF
J 0
(-4260 600);
DISPLAY 0.638298 (-4260 600);
FORCEPROP 1 LAST MATERIAL CHIP
J 0
(-4260 650);
DISPLAY 0.638298 (-4260 650);
FORCEPROP 1 LAST WATTAGE 1/16W
J 0
(-4260 700);
DISPLAY 0.638298 (-4260 700);
FORCEPROP 2 LAST CDS_LIB pure_quanta
J 0
(-4300 725);
DISPLAY INVISIBLE (-4300 725);
FORCEPROP 1 LAST PATH I40
J 0
(-4250 900);
DISPLAY 0.978723 (-4250 900);
PAINT WHITE (-4250 900);
DISPLAY INVISIBLE (-4250 900);
FORCEPROP 1 LAST PART_NUMBER CS21002FB06
J 0
(-4260 550);
DISPLAY 0.638298 (-4260 550);
DISPLAY INVISIBLE (-4260 550);
FORCEADD Q_RES..1
(-7425 1150);
FORCEPROP 1 LAST LOCATION R3688
J 0
(-7625 1150);
DISPLAY 0.638298 (-7625 1150);
FORCEPROP 0 LAST $SEC 1
J 0
(-7550 1200);
DISPLAY 0.680851 (-7550 1200);
PAINT MONO (-7550 1200);
DISPLAY INVISIBLE (-7550 1200);
FORCEPROP 0 LAST CDS_SEC 1
J 0
(-7550 1200);
DISPLAY 1.021277 (-7550 1200);
DISPLAY INVISIBLE (-7550 1200);
FORCEPROP 1 LASTPIN (-7525 1150) $PN 1
J 0
(-7513 1162);
DISPLAY 0.787234 (-7513 1162);
PAINT MONO (-7513 1162);
FORCEPROP 1 LASTPIN (-7325 1150) $PN 2
J 0
(-7363 1162);
DISPLAY 0.787234 (-7363 1162);
PAINT MONO (-7363 1162);
FORCEPROP 1 LAST TOLERANCE 5%
J 0
(-7250 1150);
DISPLAY 0.404255 (-7250 1150);
FORCEPROP 1 LAST MATERIAL CHIP
J 0
(-7200 1150);
DISPLAY 0.404255 (-7200 1150);
FORCEPROP 1 LAST VALUE 0
J 2
(-7275 1150);
DISPLAY 0.404255 (-7275 1150);
FORCEPROP 0 LAST ROOM ADC_TI_BOM1
J 0
(-7550 1100);
DISPLAY 0.553191 (-7550 1100);
PAINT RED (-7550 1100);
FORCEPROP 1 LAST PACK_TYPE 0402LF
J 0
(-7175 1150);
DISPLAY 0.510638 (-7175 1150);
DISPLAY INVISIBLE (-7175 1150);
FORCEPROP 1 LAST WATTAGE 1/16W
J 2
(-7325 1075);
DISPLAY 0.319149 (-7325 1075);
DISPLAY INVISIBLE (-7325 1075);
FORCEPROP 2 LAST CDS_LIB pure_quanta
J 0
(-7425 1150);
DISPLAY INVISIBLE (-7425 1150);
FORCEPROP 1 LAST PATH I41
J 0
(-7475 1300);
DISPLAY 0.978723 (-7475 1300);
PAINT WHITE (-7475 1300);
DISPLAY INVISIBLE (-7475 1300);
FORCEPROP 1 LAST PART_NUMBER CS00002JB13
J 0
(-7500 1100);
DISPLAY 0.319149 (-7500 1100);
DISPLAY INVISIBLE (-7500 1100);
FORCEADD Q_RES..1
(-7425 1300);
FORCEPROP 1 LAST LOCATION R3687
J 0
(-7625 1300);
DISPLAY 0.638298 (-7625 1300);
FORCEPROP 0 LAST $SEC 1
J 0
(-7550 1350);
DISPLAY 0.680851 (-7550 1350);
PAINT MONO (-7550 1350);
DISPLAY INVISIBLE (-7550 1350);
FORCEPROP 0 LAST CDS_SEC 1
J 0
(-7550 1350);
DISPLAY 1.021277 (-7550 1350);
DISPLAY INVISIBLE (-7550 1350);
FORCEPROP 1 LASTPIN (-7525 1300) $PN 1
J 0
(-7513 1312);
DISPLAY 0.787234 (-7513 1312);
PAINT MONO (-7513 1312);
FORCEPROP 1 LASTPIN (-7325 1300) $PN 2
J 0
(-7363 1312);
DISPLAY 0.787234 (-7363 1312);
PAINT MONO (-7363 1312);
FORCEPROP 1 LAST TOLERANCE 5%
J 0
(-7250 1300);
DISPLAY 0.404255 (-7250 1300);
FORCEPROP 1 LAST MATERIAL EMPTY
J 0
(-7200 1300);
DISPLAY 0.404255 (-7200 1300);
PAINT RED (-7200 1300);
FORCEPROP 1 LAST VALUE 0
J 2
(-7275 1300);
DISPLAY 0.404255 (-7275 1300);
FORCEPROP 0 LAST ROOM ADC_MAM_BOM2
J 0
(-7550 1350);
DISPLAY 0.553191 (-7550 1350);
PAINT RED (-7550 1350);
FORCEPROP 1 LAST PACK_TYPE 0402LF
J 0
(-7175 1300);
DISPLAY 0.510638 (-7175 1300);
DISPLAY INVISIBLE (-7175 1300);
FORCEPROP 1 LAST WATTAGE 1/16W
J 2
(-7325 1225);
DISPLAY 0.319149 (-7325 1225);
DISPLAY INVISIBLE (-7325 1225);
FORCEPROP 2 LAST CDS_LIB pure_quanta
J 0
(-7425 1300);
DISPLAY INVISIBLE (-7425 1300);
FORCEPROP 1 LAST PATH I42
J 0
(-7475 1450);
DISPLAY 0.978723 (-7475 1450);
PAINT WHITE (-7475 1450);
DISPLAY INVISIBLE (-7475 1450);
FORCEPROP 1 LAST PART_NUMBER CS00002JB13
J 0
(-7500 1250);
DISPLAY 0.319149 (-7500 1250);
DISPLAY INVISIBLE (-7500 1250);
FORCEADD UNIVERSAL_GND..1
(-7550 1500);
FORCEPROP 3 LASTPIN (-7550 1550) SIG_NAME GND\g
J 0
(-7540 1560);
DISPLAY 0.659574 (-7540 1560);
PAINT MONO (-7540 1560);
DISPLAY INVISIBLE (-7540 1560);
FORCEPROP 2 LAST CDS_LIB pure_quanta_power
J 0
(-7550 1500);
DISPLAY INVISIBLE (-7550 1500);
FORCEPROP 1 LAST HDL_POWER GND
J 1
(-7525 1425);
DISPLAY 0.872340 (-7525 1425);
PAINT GREEN (-7525 1425);
DISPLAY INVISIBLE (-7525 1425);
FORCEPROP 1 LAST PATH I43
J 0
(-7475 1500);
DISPLAY 0.872340 (-7475 1500);
PAINT AQUA (-7475 1500);
DISPLAY INVISIBLE (-7475 1500);
FORCEADD Q_CAP..1
R 2
(-7550 1775);
FORCEPROP 1 LAST LOCATION C2046
J 2
(-7400 1875);
DISPLAY 0.638298 (-7400 1875);
FORCEPROP 0 LAST $SEC 1
J 0
(-7450 1925);
DISPLAY 0.680851 (-7450 1925);
PAINT MONO (-7450 1925);
DISPLAY INVISIBLE (-7450 1925);
FORCEPROP 0 LAST CDS_SEC 1
J 0
(-7450 1925);
DISPLAY 1.021277 (-7450 1925);
DISPLAY INVISIBLE (-7450 1925);
FORCEPROP 1 LASTPIN (-7550 1875) $PN 1
J 2
(-7560 1855);
DISPLAY 0.787234 (-7560 1855);
PAINT MONO (-7560 1855);
FORCEPROP 1 LASTPIN (-7550 1675) $PN 2
J 2
(-7560 1655);
DISPLAY 0.787234 (-7560 1655);
PAINT MONO (-7560 1655);
FORCEPROP 1 LAST PACK_TYPE 0402
J 2
(-7375 1600);
DISPLAY 0.510638 (-7375 1600);
FORCEPROP 1 LAST MATERIAL X7R
J 2
(-7400 1700);
DISPLAY 0.510638 (-7400 1700);
PAINT RED (-7400 1700);
FORCEPROP 1 LAST VALUE 0.1UF
J 2
(-7375 1850);
DISPLAY 0.510638 (-7375 1850);
FORCEPROP 1 LAST VOLTAGE 25V
J 2
(-7400 1800);
DISPLAY 0.510638 (-7400 1800);
FORCEPROP 1 LAST TOLERANCE 10%
J 2
(-7400 1750);
DISPLAY 0.510638 (-7400 1750);
FORCEPROP 0 LAST ROOM ADC_TI_BOM1
J 0
(-7525 1575);
DISPLAY 0.553191 (-7525 1575);
PAINT RED (-7525 1575);
FORCEPROP 2 LAST CDS_LIB pure_quanta
J 0
(-7550 1775);
DISPLAY INVISIBLE (-7550 1775);
FORCEPROP 1 LAST PATH I44
J 2
(-7600 1925);
DISPLAY 0.978723 (-7600 1925);
PAINT WHITE (-7600 1925);
DISPLAY INVISIBLE (-7600 1925);
FORCEPROP 1 LAST PART_NUMBER CH4104K1B00
J 2
(-7250 1650);
DISPLAY 0.510638 (-7250 1650);
DISPLAY INVISIBLE (-7250 1650);
FORCEADD UNIVERSAL_GND..1
(-7200 1500);
FORCEPROP 3 LASTPIN (-7200 1550) SIG_NAME GND\g
J 0
(-7190 1560);
DISPLAY 0.659574 (-7190 1560);
PAINT MONO (-7190 1560);
DISPLAY INVISIBLE (-7190 1560);
FORCEPROP 2 LAST CDS_LIB pure_quanta_power
J 0
(-7200 1500);
DISPLAY INVISIBLE (-7200 1500);
FORCEPROP 1 LAST HDL_POWER GND
J 1
(-7175 1425);
DISPLAY 0.872340 (-7175 1425);
PAINT GREEN (-7175 1425);
DISPLAY INVISIBLE (-7175 1425);
FORCEPROP 1 LAST PATH I45
J 0
(-7125 1500);
DISPLAY 0.872340 (-7125 1500);
PAINT AQUA (-7125 1500);
DISPLAY INVISIBLE (-7125 1500);
FORCEADD Q_CAP..1
(-7200 1775);
FORCEPROP 1 LAST LOCATION C1344
J 0
(-7150 1875);
DISPLAY 0.510638 (-7150 1875);
FORCEPROP 2 LAST $SEC 1
J 0
(-7150 1975);
DISPLAY 0.680851 (-7150 1975);
PAINT MONO (-7150 1975);
DISPLAY INVISIBLE (-7150 1975);
FORCEPROP 0 LAST CDS_SEC 1
J 0
(-7150 1950);
DISPLAY 1.021277 (-7150 1950);
DISPLAY INVISIBLE (-7150 1950);
FORCEPROP 1 LASTPIN (-7200 1875) $PN 1
J 0
(-7190 1855);
DISPLAY 0.787234 (-7190 1855);
PAINT MONO (-7190 1855);
FORCEPROP 1 LASTPIN (-7200 1675) $PN 2
J 0
(-7190 1655);
DISPLAY 0.787234 (-7190 1655);
PAINT MONO (-7190 1655);
FORCEPROP 1 LAST VOLTAGE 50V
J 0
(-7150 1775);
DISPLAY 0.510638 (-7150 1775);
FORCEPROP 1 LAST MATERIAL EMPTY
J 0
(-7150 1675);
DISPLAY 0.510638 (-7150 1675);
FORCEPROP 1 LAST PACK_TYPE 0402
J 0
(-7150 1575);
DISPLAY 0.510638 (-7150 1575);
FORCEPROP 1 LAST TOLERANCE 5%
J 0
(-7150 1725);
DISPLAY 0.510638 (-7150 1725);
FORCEPROP 1 LAST VALUE 100PF
J 0
(-7150 1825);
DISPLAY 0.510638 (-7150 1825);
FORCEPROP 0 LAST ROOM ADC_MAM_BOM2
J 0
(-7150 1525);
DISPLAY 0.553191 (-7150 1525);
PAINT RED (-7150 1525);
FORCEPROP 2 LAST CDS_LIB pure_quanta
J 0
(-7200 1775);
DISPLAY INVISIBLE (-7200 1775);
FORCEPROP 1 LAST PATH I46
J 0
(-7150 1925);
DISPLAY 0.978723 (-7150 1925);
PAINT WHITE (-7150 1925);
DISPLAY INVISIBLE (-7150 1925);
FORCEPROP 1 LAST PART_NUMBER CH11006JB18
J 0
(-7150 1625);
DISPLAY 0.510638 (-7150 1625);
DISPLAY INVISIBLE (-7150 1625);
FORCEADD UNIVERSAL_GND..1
(-7575 2800);
FORCEPROP 3 LASTPIN (-7575 2850) SIG_NAME GND\g
J 0
(-7565 2860);
DISPLAY 0.659574 (-7565 2860);
PAINT MONO (-7565 2860);
DISPLAY INVISIBLE (-7565 2860);
FORCEPROP 2 LAST CDS_LIB pure_quanta_power
J 0
(-7575 2800);
DISPLAY INVISIBLE (-7575 2800);
FORCEPROP 1 LAST HDL_POWER GND
J 1
(-7550 2725);
DISPLAY 0.872340 (-7550 2725);
PAINT GREEN (-7550 2725);
DISPLAY INVISIBLE (-7550 2725);
FORCEPROP 1 LAST PATH I47
J 0
(-7500 2800);
DISPLAY 0.872340 (-7500 2800);
PAINT AQUA (-7500 2800);
DISPLAY INVISIBLE (-7500 2800);
FORCEADD OFFPAGE..2
(-6975 2050);
FORCEPROP 2 LAST $XR0 258 
J 0
(-6786 2050);
DISPLAY 0.638298 (-6786 2050);
PAINT MONO (-6786 2050);
FORCEPROP 2 LAST CDS_LIB standard
J 0
(-6975 2050);
DISPLAY INVISIBLE (-6975 2050);
FORCEPROP 1 LAST OFFPAGE TRUE
J 0
(-6650 1925);
DISPLAY 0.872340 (-6650 1925);
DISPLAY INVISIBLE (-6650 1925);
FORCEPROP 1 LAST COMMENT_BODY TRUE
J 0
(-7020 1955);
DISPLAY 0.872340 (-7020 1955);
PAINT GREEN (-7020 1955);
DISPLAY INVISIBLE (-7020 1955);
FORCEPROP 2 LAST PATH I48
J 0
(-6775 2100);
DISPLAY 0.680851 (-6775 2100);
DISPLAY INVISIBLE (-6775 2100);
FORCEADD OFFPAGE..2
(-6975 2200);
FORCEPROP 2 LAST $XR0 258 
J 0
(-6786 2200);
DISPLAY 0.638298 (-6786 2200);
PAINT MONO (-6786 2200);
FORCEPROP 2 LAST CDS_LIB standard
J 0
(-6975 2200);
DISPLAY INVISIBLE (-6975 2200);
FORCEPROP 1 LAST OFFPAGE TRUE
J 0
(-6650 2075);
DISPLAY 0.872340 (-6650 2075);
DISPLAY INVISIBLE (-6650 2075);
FORCEPROP 1 LAST COMMENT_BODY TRUE
J 0
(-7020 2105);
DISPLAY 0.872340 (-7020 2105);
PAINT GREEN (-7020 2105);
DISPLAY INVISIBLE (-7020 2105);
FORCEPROP 2 LAST PATH I49
J 0
(-6775 2250);
DISPLAY 0.680851 (-6775 2250);
DISPLAY INVISIBLE (-6775 2250);
FORCEADD UNIVERSAL_POWER..1
(-8925 2700);
FORCEPROP 3 LASTPIN (-8925 2650) SIG_NAME P12V_AUX\g
J 0
(-8915 2660);
DISPLAY 0.659574 (-8915 2660);
PAINT MONO (-8915 2660);
DISPLAY INVISIBLE (-8915 2660);
FORCEPROP 1 LAST HDL_POWER P12V_AUX
J 1
(-8925 2750);
DISPLAY 0.872340 (-8925 2750);
PAINT GREEN (-8925 2750);
FORCEPROP 2 LAST CDS_LIB pure_quanta_power
J 0
(-8925 2700);
DISPLAY INVISIBLE (-8925 2700);
FORCEPROP 1 LAST PATH I5
J 0
(-8875 2725);
DISPLAY 0.872340 (-8875 2725);
PAINT AQUA (-8875 2725);
DISPLAY INVISIBLE (-8875 2725);
FORCEADD OFFPAGE..2
(-6300 1150);
FORCEPROP 2 LAST $XR0 258 
J 0
(-6111 1150);
DISPLAY 0.638298 (-6111 1150);
PAINT MONO (-6111 1150);
FORCEPROP 2 LAST CDS_LIB standard
J 0
(-6300 1150);
DISPLAY INVISIBLE (-6300 1150);
FORCEPROP 1 LAST OFFPAGE TRUE
J 0
(-5975 1025);
DISPLAY 0.872340 (-5975 1025);
DISPLAY INVISIBLE (-5975 1025);
FORCEPROP 1 LAST COMMENT_BODY TRUE
J 0
(-6345 1055);
DISPLAY 0.872340 (-6345 1055);
PAINT GREEN (-6345 1055);
DISPLAY INVISIBLE (-6345 1055);
FORCEPROP 2 LAST PATH I50
J 0
(-6100 1200);
DISPLAY 0.680851 (-6100 1200);
DISPLAY INVISIBLE (-6100 1200);
FORCEADD OFFPAGE..2
(-6300 1300);
FORCEPROP 2 LAST $XR0 258 
J 0
(-6111 1300);
DISPLAY 0.638298 (-6111 1300);
PAINT MONO (-6111 1300);
FORCEPROP 2 LAST CDS_LIB standard
J 0
(-6300 1300);
DISPLAY INVISIBLE (-6300 1300);
FORCEPROP 1 LAST OFFPAGE TRUE
J 0
(-5975 1175);
DISPLAY 0.872340 (-5975 1175);
DISPLAY INVISIBLE (-5975 1175);
FORCEPROP 1 LAST COMMENT_BODY TRUE
J 0
(-6345 1205);
DISPLAY 0.872340 (-6345 1205);
PAINT GREEN (-6345 1205);
DISPLAY INVISIBLE (-6345 1205);
FORCEPROP 2 LAST PATH I51
J 0
(-6100 1350);
DISPLAY 0.680851 (-6100 1350);
DISPLAY INVISIBLE (-6100 1350);
FORCEADD Q_CAP..1
(-7575 3075);
FORCEPROP 1 LAST LOCATION C2044
J 0
(-7525 3175);
DISPLAY 0.510638 (-7525 3175);
FORCEPROP 2 LAST $SEC 1
J 0
(-7525 3275);
DISPLAY 0.680851 (-7525 3275);
PAINT MONO (-7525 3275);
DISPLAY INVISIBLE (-7525 3275);
FORCEPROP 0 LAST CDS_SEC 1
J 0
(-7525 3250);
DISPLAY 1.021277 (-7525 3250);
DISPLAY INVISIBLE (-7525 3250);
FORCEPROP 1 LASTPIN (-7575 3175) $PN 1
J 0
(-7565 3155);
DISPLAY 0.787234 (-7565 3155);
PAINT MONO (-7565 3155);
FORCEPROP 1 LASTPIN (-7575 2975) $PN 2
J 0
(-7565 2955);
DISPLAY 0.787234 (-7565 2955);
PAINT MONO (-7565 2955);
FORCEPROP 0 LAST ROOM ADC_MAM_BOM2
J 0
(-7525 2825);
DISPLAY 0.553191 (-7525 2825);
PAINT RED (-7525 2825);
FORCEPROP 1 LAST PACK_TYPE 0402
J 0
(-7525 2875);
DISPLAY 0.510638 (-7525 2875);
FORCEPROP 1 LAST MATERIAL EMPTY
J 0
(-7525 2975);
DISPLAY 0.510638 (-7525 2975);
FORCEPROP 1 LAST TOLERANCE 5%
J 0
(-7525 3025);
DISPLAY 0.510638 (-7525 3025);
FORCEPROP 1 LAST VOLTAGE 50V
J 0
(-7525 3075);
DISPLAY 0.510638 (-7525 3075);
FORCEPROP 1 LAST VALUE 100PF
J 0
(-7525 3125);
DISPLAY 0.510638 (-7525 3125);
FORCEPROP 2 LAST CDS_LIB pure_quanta
J 0
(-7575 3075);
DISPLAY INVISIBLE (-7575 3075);
FORCEPROP 1 LAST PATH I52
J 0
(-7525 3225);
DISPLAY 0.978723 (-7525 3225);
PAINT WHITE (-7525 3225);
DISPLAY INVISIBLE (-7525 3225);
FORCEPROP 1 LAST PART_NUMBER CH11006JB18
J 0
(-7525 2925);
DISPLAY 0.510638 (-7525 2925);
DISPLAY INVISIBLE (-7525 2925);
FORCEADD OFFPAGE..2
(-7450 3350);
FORCEPROP 2 LAST $XR0 258 
J 0
(-7261 3350);
DISPLAY 0.638298 (-7261 3350);
PAINT MONO (-7261 3350);
FORCEPROP 2 LAST CDS_LIB standard
J 0
(-7450 3350);
DISPLAY INVISIBLE (-7450 3350);
FORCEPROP 1 LAST OFFPAGE TRUE
J 0
(-7125 3225);
DISPLAY 0.872340 (-7125 3225);
DISPLAY INVISIBLE (-7125 3225);
FORCEPROP 1 LAST COMMENT_BODY TRUE
J 0
(-7495 3255);
DISPLAY 0.872340 (-7495 3255);
PAINT GREEN (-7495 3255);
DISPLAY INVISIBLE (-7495 3255);
FORCEPROP 2 LAST PATH I53
J 0
(-7250 3400);
DISPLAY 0.680851 (-7250 3400);
DISPLAY INVISIBLE (-7250 3400);
FORCEADD OFFPAGE..2
(-7450 3500);
FORCEPROP 2 LAST $XR0 258 
J 0
(-7261 3500);
DISPLAY 0.638298 (-7261 3500);
PAINT MONO (-7261 3500);
FORCEPROP 2 LAST CDS_LIB standard
J 0
(-7450 3500);
DISPLAY INVISIBLE (-7450 3500);
FORCEPROP 1 LAST OFFPAGE TRUE
J 0
(-7125 3375);
DISPLAY 0.872340 (-7125 3375);
DISPLAY INVISIBLE (-7125 3375);
FORCEPROP 1 LAST COMMENT_BODY TRUE
J 0
(-7495 3405);
DISPLAY 0.872340 (-7495 3405);
PAINT GREEN (-7495 3405);
DISPLAY INVISIBLE (-7495 3405);
FORCEPROP 2 LAST PATH I54
J 0
(-7250 3550);
DISPLAY 0.680851 (-7250 3550);
DISPLAY INVISIBLE (-7250 3550);
FORCEADD Q_CAP..1
(-7550 4225);
FORCEPROP 1 LAST LOCATION C2043
J 0
(-7500 4325);
DISPLAY 0.510638 (-7500 4325);
FORCEPROP 2 LAST $SEC 1
J 0
(-7500 4425);
DISPLAY 0.680851 (-7500 4425);
PAINT MONO (-7500 4425);
DISPLAY INVISIBLE (-7500 4425);
FORCEPROP 0 LAST CDS_SEC 1
J 0
(-7500 4400);
DISPLAY 1.021277 (-7500 4400);
DISPLAY INVISIBLE (-7500 4400);
FORCEPROP 1 LASTPIN (-7550 4325) $PN 1
J 0
(-7540 4305);
DISPLAY 0.787234 (-7540 4305);
PAINT MONO (-7540 4305);
FORCEPROP 1 LASTPIN (-7550 4125) $PN 2
J 0
(-7540 4105);
DISPLAY 0.787234 (-7540 4105);
PAINT MONO (-7540 4105);
FORCEPROP 1 LAST VALUE 100PF
J 0
(-7500 4275);
DISPLAY 0.510638 (-7500 4275);
FORCEPROP 1 LAST VOLTAGE 50V
J 0
(-7500 4225);
DISPLAY 0.510638 (-7500 4225);
FORCEPROP 1 LAST TOLERANCE 5%
J 0
(-7500 4175);
DISPLAY 0.510638 (-7500 4175);
FORCEPROP 1 LAST MATERIAL EMPTY
J 0
(-7500 4125);
DISPLAY 0.510638 (-7500 4125);
FORCEPROP 1 LAST PACK_TYPE 0402
J 0
(-7500 4025);
DISPLAY 0.510638 (-7500 4025);
FORCEPROP 0 LAST ROOM ADC_MAM_BOM2
J 0
(-7500 4000);
DISPLAY 0.553191 (-7500 4000);
PAINT RED (-7500 4000);
FORCEPROP 2 LAST CDS_LIB pure_quanta
J 0
(-7550 4225);
DISPLAY INVISIBLE (-7550 4225);
FORCEPROP 1 LAST PATH I55
J 0
(-7500 4375);
DISPLAY 0.978723 (-7500 4375);
PAINT WHITE (-7500 4375);
DISPLAY INVISIBLE (-7500 4375);
FORCEPROP 1 LAST PART_NUMBER CH11006JB18
J 0
(-7500 4075);
DISPLAY 0.510638 (-7500 4075);
DISPLAY INVISIBLE (-7500 4075);
FORCEADD UNIVERSAL_GND..1
(-7550 3950);
FORCEPROP 3 LASTPIN (-7550 4000) SIG_NAME GND\g
J 0
(-7540 4010);
DISPLAY 0.659574 (-7540 4010);
PAINT MONO (-7540 4010);
DISPLAY INVISIBLE (-7540 4010);
FORCEPROP 2 LAST CDS_LIB pure_quanta_power
J 0
(-7550 3950);
DISPLAY INVISIBLE (-7550 3950);
FORCEPROP 1 LAST HDL_POWER GND
J 1
(-7525 3875);
DISPLAY 0.872340 (-7525 3875);
PAINT GREEN (-7525 3875);
DISPLAY INVISIBLE (-7525 3875);
FORCEPROP 1 LAST PATH I56
J 0
(-7475 3950);
DISPLAY 0.872340 (-7475 3950);
PAINT AQUA (-7475 3950);
DISPLAY INVISIBLE (-7475 3950);
FORCEADD OFFPAGE..2
(-7450 4500);
FORCEPROP 2 LAST $XR0 258 
J 0
(-7261 4500);
DISPLAY 0.638298 (-7261 4500);
PAINT MONO (-7261 4500);
FORCEPROP 2 LAST CDS_LIB standard
J 0
(-7450 4500);
DISPLAY INVISIBLE (-7450 4500);
FORCEPROP 1 LAST OFFPAGE TRUE
J 0
(-7125 4375);
DISPLAY 0.872340 (-7125 4375);
DISPLAY INVISIBLE (-7125 4375);
FORCEPROP 1 LAST COMMENT_BODY TRUE
J 0
(-7495 4405);
DISPLAY 0.872340 (-7495 4405);
PAINT GREEN (-7495 4405);
DISPLAY INVISIBLE (-7495 4405);
FORCEPROP 2 LAST PATH I57
J 0
(-7250 4550);
DISPLAY 0.680851 (-7250 4550);
DISPLAY INVISIBLE (-7250 4550);
FORCEADD OFFPAGE..2
(-7450 4650);
FORCEPROP 2 LAST $XR0 258 
J 0
(-7261 4650);
DISPLAY 0.638298 (-7261 4650);
PAINT MONO (-7261 4650);
FORCEPROP 2 LAST CDS_LIB standard
J 0
(-7450 4650);
DISPLAY INVISIBLE (-7450 4650);
FORCEPROP 1 LAST OFFPAGE TRUE
J 0
(-7125 4525);
DISPLAY 0.872340 (-7125 4525);
DISPLAY INVISIBLE (-7125 4525);
FORCEPROP 1 LAST COMMENT_BODY TRUE
J 0
(-7495 4555);
DISPLAY 0.872340 (-7495 4555);
PAINT GREEN (-7495 4555);
DISPLAY INVISIBLE (-7495 4555);
FORCEPROP 2 LAST PATH I58
J 0
(-7250 4700);
DISPLAY 0.680851 (-7250 4700);
DISPLAY INVISIBLE (-7250 4700);
FORCEADD OFFPAGE..1
(-6625 3375);
FORCEPROP 2 LAST $XR0 147 
J 0
(-6877 3375);
DISPLAY 0.638298 (-6877 3375);
PAINT MONO (-6877 3375);
FORCEPROP 2 LAST CDS_LIB standard
J 0
(-6625 3375);
DISPLAY INVISIBLE (-6625 3375);
FORCEPROP 1 LAST OFFPAGE TRUE
J 0
(-6300 3250);
DISPLAY 0.872340 (-6300 3250);
PAINT GREEN (-6300 3250);
DISPLAY INVISIBLE (-6300 3250);
FORCEPROP 1 LAST COMMENT_BODY TRUE
J 0
(-6500 3275);
DISPLAY 0.872340 (-6500 3275);
PAINT GREEN (-6500 3275);
DISPLAY INVISIBLE (-6500 3275);
FORCEPROP 2 LAST PATH I59
J 0
(-6875 3425);
DISPLAY 0.680851 (-6875 3425);
DISPLAY INVISIBLE (-6875 3425);
FORCEADD Q_RES..2
(-8925 2450);
FORCEPROP 1 LAST LOCATION R1799
J 0
(-8880 2575);
DISPLAY 0.510638 (-8880 2575);
FORCEPROP 2 LAST $SEC 1
J 0
(-8875 2675);
DISPLAY 0.680851 (-8875 2675);
PAINT MONO (-8875 2675);
DISPLAY INVISIBLE (-8875 2675);
FORCEPROP 0 LAST CDS_SEC 1
J 0
(-8875 2625);
DISPLAY 1.021277 (-8875 2625);
DISPLAY INVISIBLE (-8875 2625);
FORCEPROP 1 LASTPIN (-8925 2550) $PN 1
J 0
(-8920 2512);
DISPLAY 0.787234 (-8920 2512);
PAINT MONO (-8920 2512);
FORCEPROP 1 LASTPIN (-8925 2350) $PN 2
J 0
(-8920 2360);
DISPLAY 0.787234 (-8920 2360);
PAINT MONO (-8920 2360);
FORCEPROP 1 LAST VALUE 7.87K
J 0
(-8880 2525);
DISPLAY 0.510638 (-8880 2525);
FORCEPROP 1 LAST WATTAGE 1/16W
J 0
(-8885 2425);
DISPLAY 0.510638 (-8885 2425);
FORCEPROP 1 LAST TOLERANCE 1%
J 0
(-8880 2475);
DISPLAY 0.510638 (-8880 2475);
FORCEPROP 1 LAST MATERIAL CHIP
J 0
(-8885 2375);
DISPLAY 0.510638 (-8885 2375);
FORCEPROP 1 LAST PACK_TYPE 0402LF
J 0
(-8885 2275);
DISPLAY 0.510638 (-8885 2275);
FORCEPROP 2 LAST CDS_LIB pure_quanta
J 0
(-8925 2450);
DISPLAY INVISIBLE (-8925 2450);
FORCEPROP 1 LAST PATH I6
J 0
(-8875 2625);
DISPLAY 0.978723 (-8875 2625);
PAINT WHITE (-8875 2625);
DISPLAY INVISIBLE (-8875 2625);
FORCEPROP 1 LAST PART_NUMBER CS27872FB02
J 0
(-8885 2325);
DISPLAY 0.510638 (-8885 2325);
DISPLAY INVISIBLE (-8885 2325);
FORCEADD OFFPAGE..1
(-6625 3525);
FORCEPROP 2 LAST $XR0 146 
J 0
(-6877 3525);
DISPLAY 0.638298 (-6877 3525);
PAINT MONO (-6877 3525);
FORCEPROP 2 LAST CDS_LIB standard
J 0
(-6625 3525);
DISPLAY INVISIBLE (-6625 3525);
FORCEPROP 1 LAST OFFPAGE TRUE
J 0
(-6300 3400);
DISPLAY 0.872340 (-6300 3400);
PAINT GREEN (-6300 3400);
DISPLAY INVISIBLE (-6300 3400);
FORCEPROP 1 LAST COMMENT_BODY TRUE
J 0
(-6500 3425);
DISPLAY 0.872340 (-6500 3425);
PAINT GREEN (-6500 3425);
DISPLAY INVISIBLE (-6500 3425);
FORCEPROP 2 LAST PATH I60
J 0
(-6875 3575);
DISPLAY 0.680851 (-6875 3575);
DISPLAY INVISIBLE (-6875 3575);
FORCEADD OFFPAGE..1
(-6625 3875);
FORCEPROP 2 LAST $XR0 147 
J 0
(-6877 3875);
DISPLAY 0.638298 (-6877 3875);
PAINT MONO (-6877 3875);
FORCEPROP 2 LAST CDS_LIB standard
J 0
(-6625 3875);
DISPLAY INVISIBLE (-6625 3875);
FORCEPROP 1 LAST OFFPAGE TRUE
J 0
(-6300 3750);
DISPLAY 0.872340 (-6300 3750);
PAINT GREEN (-6300 3750);
DISPLAY INVISIBLE (-6300 3750);
FORCEPROP 1 LAST COMMENT_BODY TRUE
J 0
(-6500 3775);
DISPLAY 0.872340 (-6500 3775);
PAINT GREEN (-6500 3775);
DISPLAY INVISIBLE (-6500 3775);
FORCEPROP 2 LAST PATH I61
J 0
(-6875 3925);
DISPLAY 0.680851 (-6875 3925);
DISPLAY INVISIBLE (-6875 3925);
FORCEADD OFFPAGE..1
(-6625 4025);
FORCEPROP 2 LAST $XR0 146 
J 0
(-6877 4025);
DISPLAY 0.638298 (-6877 4025);
PAINT MONO (-6877 4025);
FORCEPROP 2 LAST CDS_LIB standard
J 0
(-6625 4025);
DISPLAY INVISIBLE (-6625 4025);
FORCEPROP 1 LAST OFFPAGE TRUE
J 0
(-6300 3900);
DISPLAY 0.872340 (-6300 3900);
PAINT GREEN (-6300 3900);
DISPLAY INVISIBLE (-6300 3900);
FORCEPROP 1 LAST COMMENT_BODY TRUE
J 0
(-6500 3925);
DISPLAY 0.872340 (-6500 3925);
PAINT GREEN (-6500 3925);
DISPLAY INVISIBLE (-6500 3925);
FORCEPROP 2 LAST PATH I62
J 0
(-6875 4075);
DISPLAY 0.680851 (-6875 4075);
DISPLAY INVISIBLE (-6875 4075);
FORCEADD OFFPAGE..1
(-6600 4375);
FORCEPROP 2 LAST $XR0 141 
J 0
(-6852 4375);
DISPLAY 0.638298 (-6852 4375);
PAINT MONO (-6852 4375);
FORCEPROP 2 LAST CDS_LIB standard
J 0
(-6600 4375);
DISPLAY INVISIBLE (-6600 4375);
FORCEPROP 1 LAST OFFPAGE TRUE
J 0
(-6275 4250);
DISPLAY 0.872340 (-6275 4250);
PAINT GREEN (-6275 4250);
DISPLAY INVISIBLE (-6275 4250);
FORCEPROP 1 LAST COMMENT_BODY TRUE
J 0
(-6475 4275);
DISPLAY 0.872340 (-6475 4275);
PAINT GREEN (-6475 4275);
DISPLAY INVISIBLE (-6475 4275);
FORCEPROP 2 LAST PATH I63
J 0
(-6850 4425);
DISPLAY 0.680851 (-6850 4425);
DISPLAY INVISIBLE (-6850 4425);
FORCEADD OFFPAGE..1
(-6600 4525);
FORCEPROP 2 LAST $XR0 140 
J 0
(-6852 4525);
DISPLAY 0.638298 (-6852 4525);
PAINT MONO (-6852 4525);
FORCEPROP 2 LAST CDS_LIB standard
J 0
(-6600 4525);
DISPLAY INVISIBLE (-6600 4525);
FORCEPROP 1 LAST OFFPAGE TRUE
J 0
(-6275 4400);
DISPLAY 0.872340 (-6275 4400);
PAINT GREEN (-6275 4400);
DISPLAY INVISIBLE (-6275 4400);
FORCEPROP 1 LAST COMMENT_BODY TRUE
J 0
(-6475 4425);
DISPLAY 0.872340 (-6475 4425);
PAINT GREEN (-6475 4425);
DISPLAY INVISIBLE (-6475 4425);
FORCEPROP 2 LAST PATH I64
J 0
(-6850 4575);
DISPLAY 0.680851 (-6850 4575);
DISPLAY INVISIBLE (-6850 4575);
FORCEADD OFFPAGE..1
(-6600 4875);
FORCEPROP 2 LAST $XR0 141 
J 0
(-6852 4875);
DISPLAY 0.638298 (-6852 4875);
PAINT MONO (-6852 4875);
FORCEPROP 2 LAST CDS_LIB standard
J 0
(-6600 4875);
DISPLAY INVISIBLE (-6600 4875);
FORCEPROP 1 LAST OFFPAGE TRUE
J 0
(-6275 4750);
DISPLAY 0.872340 (-6275 4750);
PAINT GREEN (-6275 4750);
DISPLAY INVISIBLE (-6275 4750);
FORCEPROP 1 LAST COMMENT_BODY TRUE
J 0
(-6475 4775);
DISPLAY 0.872340 (-6475 4775);
PAINT GREEN (-6475 4775);
DISPLAY INVISIBLE (-6475 4775);
FORCEPROP 2 LAST PATH I65
J 0
(-6850 4925);
DISPLAY 0.680851 (-6850 4925);
DISPLAY INVISIBLE (-6850 4925);
FORCEADD Q_RES..2
(-4550 1325);
FORCEPROP 1 LAST LOCATION R3667
J 0
(-4505 1450);
DISPLAY 0.638298 (-4505 1450);
FORCEPROP 0 LAST $SEC 1
J 0
(-4500 1500);
DISPLAY 0.680851 (-4500 1500);
PAINT MONO (-4500 1500);
DISPLAY INVISIBLE (-4500 1500);
FORCEPROP 0 LAST CDS_SEC 1
J 0
(-4500 1500);
DISPLAY 1.021277 (-4500 1500);
DISPLAY INVISIBLE (-4500 1500);
FORCEPROP 1 LASTPIN (-4550 1425) $PN 1
J 0
(-4545 1387);
DISPLAY 0.787234 (-4545 1387);
PAINT MONO (-4545 1387);
FORCEPROP 1 LASTPIN (-4550 1225) $PN 2
J 0
(-4545 1235);
DISPLAY 0.787234 (-4545 1235);
PAINT MONO (-4545 1235);
FORCEPROP 0 LAST ROOM ADC_TI_BOM1
J 0
(-4600 1500);
DISPLAY 0.446809 (-4600 1500);
PAINT RED (-4600 1500);
FORCEPROP 1 LAST PACK_TYPE 0402LF
J 0
(-4510 1200);
DISPLAY 0.638298 (-4510 1200);
FORCEPROP 1 LAST VALUE 1K
J 0
(-4505 1400);
DISPLAY 0.638298 (-4505 1400);
FORCEPROP 1 LAST MATERIAL EMPTY
J 0
(-4510 1250);
DISPLAY 0.638298 (-4510 1250);
PAINT RED (-4510 1250);
FORCEPROP 1 LAST TOLERANCE 1%
J 0
(-4505 1350);
DISPLAY 0.638298 (-4505 1350);
FORCEPROP 1 LAST WATTAGE 1/16W
J 0
(-4510 1300);
DISPLAY 0.638298 (-4510 1300);
FORCEPROP 2 LAST CDS_LIB pure_quanta
J 0
(-4550 1325);
DISPLAY INVISIBLE (-4550 1325);
FORCEPROP 1 LAST PATH I66
J 0
(-4500 1500);
DISPLAY 0.978723 (-4500 1500);
PAINT WHITE (-4500 1500);
DISPLAY INVISIBLE (-4500 1500);
FORCEPROP 1 LAST PART_NUMBER CS21002FB06
J 0
(-4510 1150);
DISPLAY 0.638298 (-4510 1150);
DISPLAY INVISIBLE (-4510 1150);
FORCEADD UNIVERSAL_POWER..1
(-4550 1725);
FORCEPROP 3 LASTPIN (-4550 1675) SIG_NAME P3V3_AUX\g
J 0
(-4540 1685);
DISPLAY 0.659574 (-4540 1685);
PAINT MONO (-4540 1685);
DISPLAY INVISIBLE (-4540 1685);
FORCEPROP 1 LAST HDL_POWER P3V3_AUX
J 1
(-4550 1775);
DISPLAY 0.872340 (-4550 1775);
PAINT GREEN (-4550 1775);
FORCEPROP 2 LAST CDS_LIB pure_quanta_power
J 0
(-4550 1725);
PAINT MONO (-4550 1725);
DISPLAY INVISIBLE (-4550 1725);
FORCEPROP 1 LAST PATH I67
J 0
(-4500 1750);
DISPLAY 0.872340 (-4500 1750);
PAINT AQUA (-4500 1750);
DISPLAY INVISIBLE (-4500 1750);
FORCEADD Q_RES..2
(-4300 1325);
FORCEPROP 1 LAST LOCATION R3669
J 0
(-4255 1450);
DISPLAY 0.638298 (-4255 1450);
FORCEPROP 0 LAST $SEC 1
J 0
(-4250 1500);
DISPLAY 0.680851 (-4250 1500);
PAINT MONO (-4250 1500);
DISPLAY INVISIBLE (-4250 1500);
FORCEPROP 0 LAST CDS_SEC 1
J 0
(-4250 1500);
DISPLAY 1.021277 (-4250 1500);
DISPLAY INVISIBLE (-4250 1500);
FORCEPROP 1 LASTPIN (-4300 1425) $PN 1
J 0
(-4295 1387);
DISPLAY 0.787234 (-4295 1387);
PAINT MONO (-4295 1387);
FORCEPROP 1 LASTPIN (-4300 1225) $PN 2
J 0
(-4295 1235);
DISPLAY 0.787234 (-4295 1235);
PAINT MONO (-4295 1235);
FORCEPROP 1 LAST MATERIAL EMPTY
J 0
(-4260 1250);
DISPLAY 0.638298 (-4260 1250);
PAINT RED (-4260 1250);
FORCEPROP 1 LAST PACK_TYPE 0402LF
J 0
(-4260 1200);
DISPLAY 0.638298 (-4260 1200);
FORCEPROP 1 LAST VALUE 1K
J 0
(-4255 1400);
DISPLAY 0.638298 (-4255 1400);
FORCEPROP 1 LAST TOLERANCE 1%
J 0
(-4255 1350);
DISPLAY 0.638298 (-4255 1350);
FORCEPROP 1 LAST WATTAGE 1/16W
J 0
(-4260 1300);
DISPLAY 0.638298 (-4260 1300);
FORCEPROP 0 LAST ROOM ADC_TI_BOM1
J 0
(-4250 1500);
DISPLAY 0.553191 (-4250 1500);
PAINT RED (-4250 1500);
FORCEPROP 2 LAST CDS_LIB pure_quanta
J 0
(-4300 1325);
DISPLAY INVISIBLE (-4300 1325);
FORCEPROP 1 LAST PATH I68
J 0
(-4250 1500);
DISPLAY 0.978723 (-4250 1500);
PAINT WHITE (-4250 1500);
DISPLAY INVISIBLE (-4250 1500);
FORCEPROP 1 LAST PART_NUMBER CS21002FB06
J 0
(-4260 1150);
DISPLAY 0.638298 (-4260 1150);
DISPLAY INVISIBLE (-4260 1150);
FORCEADD Q_INDUCTOR..1
(-4350 2725);
FORCEPROP 1 LAST LOCATION L16
J 0
(-4475 2885);
DISPLAY 0.723404 (-4475 2885);
PAINT GREEN (-4475 2885);
FORCEPROP 0 LAST $SEC 1
J 0
(-4450 3000);
DISPLAY 0.680851 (-4450 3000);
PAINT MONO (-4450 3000);
DISPLAY INVISIBLE (-4450 3000);
FORCEPROP 0 LAST CDS_SEC 1
J 0
(-4450 3000);
DISPLAY 1.021277 (-4450 3000);
DISPLAY INVISIBLE (-4450 3000);
FORCEPROP 0 LASTPIN (-4450 2700) $PN 1
J 2
(-4460 2710);
DISPLAY 0.680851 (-4460 2710);
PAINT MONO (-4460 2710);
FORCEPROP 0 LASTPIN (-4250 2700) $PN 2
J 0
(-4240 2710);
DISPLAY 0.680851 (-4240 2710);
PAINT MONO (-4240 2710);
FORCEPROP 1 LAST MATERIAL IND
J 0
(-4450 2780);
DISPLAY 0.382979 (-4450 2780);
PAINT RED (-4450 2780);
FORCEPROP 2 LAST PACK_TYPE SMLF
J 0
(-4450 2925);
DISPLAY 0.510638 (-4450 2925);
FORCEPROP 2 LAST VALUE BLM18PG300SN1D 
J 0
(-4450 2975);
DISPLAY 0.510638 (-4450 2975);
FORCEPROP 0 LAST ROOM ADC_TI_BOM1
J 0
(-4450 3050);
DISPLAY 0.680851 (-4450 3050);
PAINT RED (-4450 3050);
FORCEPROP 1 LAST NEEDS_NO_SIZE TRUE
J 0
(-4350 2725);
DISPLAY 0.468085 (-4350 2725);
PAINT GREEN (-4350 2725);
DISPLAY INVISIBLE (-4350 2725);
FORCEPROP 2 LAST CDS_LIB pure_quanta
J 0
(-4350 2725);
DISPLAY INVISIBLE (-4350 2725);
FORCEPROP 1 LAST PATH I69
J 0
(-4275 2780);
DISPLAY 0.723404 (-4275 2780);
PAINT GREEN (-4275 2780);
DISPLAY INVISIBLE (-4275 2780);
FORCEPROP 1 LAST PART_NUMBER TMP_QCX8PG300001
J 0
(-4450 2835);
DISPLAY 0.382979 (-4450 2835);
PAINT GREEN (-4450 2835);
DISPLAY INVISIBLE (-4450 2835);
FORCEADD Q_RES..2
(-8375 950);
PAINT ORANGE (-8375 950);
FORCEPROP 1 LAST LOCATION R4568
J 0
(-8330 1075);
DISPLAY 0.638298 (-8330 1075);
FORCEPROP 0 LAST $SEC 1
J 0
(-8325 1125);
DISPLAY 0.680851 (-8325 1125);
PAINT MONO (-8325 1125);
DISPLAY INVISIBLE (-8325 1125);
FORCEPROP 0 LAST CDS_SEC 1
J 0
(-8325 1125);
DISPLAY 1.021277 (-8325 1125);
DISPLAY INVISIBLE (-8325 1125);
FORCEPROP 1 LASTPIN (-8375 1050) $PN 1
J 0
(-8370 1012);
DISPLAY 0.787234 (-8370 1012);
PAINT MONO (-8370 1012);
FORCEPROP 1 LASTPIN (-8375 850) $PN 2
J 0
(-8370 860);
DISPLAY 0.787234 (-8370 860);
PAINT MONO (-8370 860);
FORCEPROP 1 LAST TOLERANCE 1%
J 0
(-8330 975);
DISPLAY 0.638298 (-8330 975);
FORCEPROP 1 LAST VALUE 4.7K
J 0
(-8330 1025);
DISPLAY 0.638298 (-8330 1025);
FORCEPROP 1 LAST MATERIAL CHIP
J 0
(-8325 875);
DISPLAY 0.638298 (-8325 875);
FORCEPROP 1 LAST WATTAGE 1/16W
J 0
(-8335 925);
DISPLAY 0.638298 (-8335 925);
FORCEPROP 1 LAST PACK_TYPE 0402LF
J 0
(-8335 775);
DISPLAY 0.638298 (-8335 775);
FORCEPROP 2 LAST CDS_LIB pure_quanta
J 0
(-8375 950);
DISPLAY INVISIBLE (-8375 950);
FORCEPROP 1 LAST PATH I7
J 0
(-8325 1125);
DISPLAY 0.978723 (-8325 1125);
PAINT WHITE (-8325 1125);
DISPLAY INVISIBLE (-8325 1125);
FORCEPROP 1 LAST PART_NUMBER CS24702FB06
J 0
(-8335 825);
DISPLAY 0.638298 (-8335 825);
DISPLAY INVISIBLE (-8335 825);
FORCEADD UNIVERSAL_GND..1
(-4175 2175);
FORCEPROP 3 LASTPIN (-4175 2225) SIG_NAME GND\g
J 0
(-4165 2235);
DISPLAY 0.659574 (-4165 2235);
PAINT MONO (-4165 2235);
DISPLAY INVISIBLE (-4165 2235);
FORCEPROP 2 LAST CDS_LIB pure_quanta_power
J 0
(-4175 2175);
DISPLAY INVISIBLE (-4175 2175);
FORCEPROP 1 LAST HDL_POWER GND
J 1
(-4150 2100);
DISPLAY 0.872340 (-4150 2100);
PAINT GREEN (-4150 2100);
DISPLAY INVISIBLE (-4150 2100);
FORCEPROP 1 LAST PATH I70
J 0
(-4100 2175);
DISPLAY 0.872340 (-4100 2175);
PAINT AQUA (-4100 2175);
DISPLAY INVISIBLE (-4100 2175);
FORCEADD Q_CAP..1
R 2
(-4175 2500);
FORCEPROP 1 LAST LOCATION C2051
J 2
(-3950 2625);
DISPLAY 0.978723 (-3950 2625);
FORCEPROP 0 LAST $SEC 1
J 0
(-4075 2650);
DISPLAY 0.680851 (-4075 2650);
PAINT MONO (-4075 2650);
DISPLAY INVISIBLE (-4075 2650);
FORCEPROP 0 LAST CDS_SEC 1
J 0
(-4075 2650);
DISPLAY 1.021277 (-4075 2650);
DISPLAY INVISIBLE (-4075 2650);
FORCEPROP 1 LASTPIN (-4175 2600) $PN 1
J 2
(-4185 2580);
DISPLAY 0.787234 (-4185 2580);
PAINT MONO (-4185 2580);
FORCEPROP 1 LASTPIN (-4175 2400) $PN 2
J 2
(-4185 2380);
DISPLAY 0.787234 (-4185 2380);
PAINT MONO (-4185 2380);
FORCEPROP 1 LAST TOLERANCE 10%
J 2
(-4025 2475);
DISPLAY 0.510638 (-4025 2475);
FORCEPROP 0 LAST ROOM ADC_TI_BOM1
J 0
(-4150 2275);
DISPLAY 0.553191 (-4150 2275);
PAINT RED (-4150 2275);
FORCEPROP 1 LAST VOLTAGE 25V
J 2
(-4025 2525);
DISPLAY 0.510638 (-4025 2525);
FORCEPROP 1 LAST MATERIAL X7R
J 2
(-4025 2425);
DISPLAY 0.510638 (-4025 2425);
PAINT RED (-4025 2425);
FORCEPROP 1 LAST VALUE 0.1UF
J 2
(-4000 2575);
DISPLAY 0.510638 (-4000 2575);
FORCEPROP 1 LAST PACK_TYPE 0402
J 2
(-4000 2325);
DISPLAY 0.510638 (-4000 2325);
FORCEPROP 2 LAST CDS_LIB pure_quanta
J 0
(-4175 2500);
DISPLAY INVISIBLE (-4175 2500);
FORCEPROP 1 LAST PATH I71
J 2
(-4225 2650);
DISPLAY 0.978723 (-4225 2650);
PAINT WHITE (-4225 2650);
DISPLAY INVISIBLE (-4225 2650);
FORCEPROP 1 LAST PART_NUMBER CH4104K1B00
J 2
(-3875 2375);
DISPLAY 0.510638 (-3875 2375);
DISPLAY INVISIBLE (-3875 2375);
FORCEADD Q_CAP..1
(-3850 2500);
FORCEPROP 1 LAST LOCATION C2052
J 0
(-3800 2600);
DISPLAY 0.978723 (-3800 2600);
FORCEPROP 0 LAST $SEC 1
J 0
(-3800 2650);
DISPLAY 0.680851 (-3800 2650);
PAINT MONO (-3800 2650);
DISPLAY INVISIBLE (-3800 2650);
FORCEPROP 0 LAST CDS_SEC 1
J 0
(-3800 2650);
DISPLAY 1.021277 (-3800 2650);
DISPLAY INVISIBLE (-3800 2650);
FORCEPROP 1 LASTPIN (-3850 2600) $PN 1
J 0
(-3840 2580);
DISPLAY 0.787234 (-3840 2580);
PAINT MONO (-3840 2580);
FORCEPROP 1 LASTPIN (-3850 2400) $PN 2
J 0
(-3840 2380);
DISPLAY 0.787234 (-3840 2380);
PAINT MONO (-3840 2380);
FORCEPROP 1 LAST MATERIAL X7R
J 0
(-3800 2400);
DISPLAY 0.510638 (-3800 2400);
PAINT RED (-3800 2400);
FORCEPROP 1 LAST VOLTAGE 25V
J 0
(-3800 2500);
DISPLAY 0.510638 (-3800 2500);
FORCEPROP 1 LAST VALUE 0.1UF
J 0
(-3800 2550);
DISPLAY 0.510638 (-3800 2550);
FORCEPROP 1 LAST TOLERANCE 10%
J 0
(-3800 2450);
DISPLAY 0.510638 (-3800 2450);
FORCEPROP 0 LAST ROOM ADC_TI_BOM1
J 0
(-3800 2250);
DISPLAY 0.553191 (-3800 2250);
PAINT RED (-3800 2250);
FORCEPROP 1 LAST PACK_TYPE 0402
J 0
(-3800 2300);
DISPLAY 0.510638 (-3800 2300);
FORCEPROP 2 LAST CDS_LIB pure_quanta
J 0
(-3850 2500);
DISPLAY INVISIBLE (-3850 2500);
FORCEPROP 1 LAST PATH I72
J 0
(-3800 2650);
DISPLAY 0.978723 (-3800 2650);
PAINT WHITE (-3800 2650);
DISPLAY INVISIBLE (-3800 2650);
FORCEPROP 1 LAST PART_NUMBER CH4104K1B00
J 0
(-3800 2350);
DISPLAY 0.510638 (-3800 2350);
DISPLAY INVISIBLE (-3800 2350);
FORCEADD Q_RES..1
(-5700 3375);
FORCEPROP 1 LAST LOCATION R3942
J 0
(-5875 3375);
DISPLAY 0.510638 (-5875 3375);
FORCEPROP 0 LAST $SEC 1
J 0
(-5825 3425);
DISPLAY 0.680851 (-5825 3425);
PAINT MONO (-5825 3425);
DISPLAY INVISIBLE (-5825 3425);
FORCEPROP 0 LAST CDS_SEC 1
J 0
(-5825 3425);
DISPLAY 1.021277 (-5825 3425);
DISPLAY INVISIBLE (-5825 3425);
FORCEPROP 1 LASTPIN (-5800 3375) $PN 1
J 0
(-5788 3387);
DISPLAY 0.787234 (-5788 3387);
PAINT MONO (-5788 3387);
FORCEPROP 1 LASTPIN (-5600 3375) $PN 2
J 0
(-5638 3387);
DISPLAY 0.787234 (-5638 3387);
PAINT MONO (-5638 3387);
FORCEPROP 1 LAST TOLERANCE 5%
J 0
(-5525 3375);
DISPLAY 0.404255 (-5525 3375);
FORCEPROP 1 LAST VALUE 0
J 2
(-5550 3375);
DISPLAY 0.404255 (-5550 3375);
FORCEPROP 1 LAST MATERIAL EMPTY
J 0
(-5475 3375);
DISPLAY 0.404255 (-5475 3375);
PAINT RED (-5475 3375);
FORCEPROP 0 LAST ROOM ADC_TI_BOM3
J 0
(-5825 3325);
DISPLAY 0.553191 (-5825 3325);
PAINT RED (-5825 3325);
FORCEPROP 1 LAST PACK_TYPE 0402LF
J 0
(-5450 3375);
DISPLAY 0.510638 (-5450 3375);
DISPLAY INVISIBLE (-5450 3375);
FORCEPROP 1 LAST WATTAGE 1/16W
J 2
(-5600 3300);
DISPLAY 0.319149 (-5600 3300);
DISPLAY INVISIBLE (-5600 3300);
FORCEPROP 2 LAST CDS_LIB pure_quanta
J 0
(-5700 3375);
DISPLAY INVISIBLE (-5700 3375);
FORCEPROP 1 LAST PATH I73
J 0
(-5750 3525);
DISPLAY 0.978723 (-5750 3525);
PAINT WHITE (-5750 3525);
DISPLAY INVISIBLE (-5750 3525);
FORCEPROP 1 LAST PART_NUMBER CS00002JB13
J 0
(-5775 3325);
DISPLAY 0.319149 (-5775 3325);
DISPLAY INVISIBLE (-5775 3325);
FORCEADD Q_RES..1
(-5700 3525);
FORCEPROP 1 LAST LOCATION R3941
J 0
(-5875 3525);
DISPLAY 0.510638 (-5875 3525);
FORCEPROP 0 LAST $SEC 1
J 0
(-5825 3575);
DISPLAY 0.680851 (-5825 3575);
PAINT MONO (-5825 3575);
DISPLAY INVISIBLE (-5825 3575);
FORCEPROP 0 LAST CDS_SEC 1
J 0
(-5825 3575);
DISPLAY 1.021277 (-5825 3575);
DISPLAY INVISIBLE (-5825 3575);
FORCEPROP 1 LASTPIN (-5800 3525) $PN 1
J 0
(-5788 3537);
DISPLAY 0.787234 (-5788 3537);
PAINT MONO (-5788 3537);
FORCEPROP 1 LASTPIN (-5600 3525) $PN 2
J 0
(-5638 3537);
DISPLAY 0.787234 (-5638 3537);
PAINT MONO (-5638 3537);
FORCEPROP 1 LAST TOLERANCE 5%
J 0
(-5525 3525);
DISPLAY 0.404255 (-5525 3525);
FORCEPROP 1 LAST VALUE 0
J 2
(-5550 3525);
DISPLAY 0.404255 (-5550 3525);
FORCEPROP 1 LAST MATERIAL CHIP
J 0
(-5475 3525);
DISPLAY 0.404255 (-5475 3525);
FORCEPROP 0 LAST ROOM ADC_TI_BOM1
J 0
(-5825 3600);
DISPLAY 0.553191 (-5825 3600);
PAINT RED (-5825 3600);
FORCEPROP 1 LAST PACK_TYPE 0402LF
J 0
(-5450 3525);
DISPLAY 0.510638 (-5450 3525);
DISPLAY INVISIBLE (-5450 3525);
FORCEPROP 1 LAST WATTAGE 1/16W
J 2
(-5600 3450);
DISPLAY 0.319149 (-5600 3450);
DISPLAY INVISIBLE (-5600 3450);
FORCEPROP 2 LAST CDS_LIB pure_quanta
J 0
(-5700 3525);
DISPLAY INVISIBLE (-5700 3525);
FORCEPROP 1 LAST PATH I74
J 0
(-5750 3675);
DISPLAY 0.978723 (-5750 3675);
PAINT WHITE (-5750 3675);
DISPLAY INVISIBLE (-5750 3675);
FORCEPROP 1 LAST PART_NUMBER CS00002JB13
J 0
(-5775 3475);
DISPLAY 0.319149 (-5775 3475);
DISPLAY INVISIBLE (-5775 3475);
FORCEADD UNIVERSAL_GND..1
(-5000 3175);
FORCEPROP 3 LASTPIN (-5000 3225) SIG_NAME GND\g
J 0
(-4990 3235);
DISPLAY 0.659574 (-4990 3235);
PAINT MONO (-4990 3235);
DISPLAY INVISIBLE (-4990 3235);
FORCEPROP 2 LAST CDS_LIB pure_quanta_power
J 0
(-5000 3175);
DISPLAY INVISIBLE (-5000 3175);
FORCEPROP 1 LAST HDL_POWER GND
J 1
(-4975 3100);
DISPLAY 0.872340 (-4975 3100);
PAINT GREEN (-4975 3100);
DISPLAY INVISIBLE (-4975 3100);
FORCEPROP 1 LAST PATH I75
J 0
(-4925 3175);
DISPLAY 0.872340 (-4925 3175);
PAINT AQUA (-4925 3175);
DISPLAY INVISIBLE (-4925 3175);
FORCEADD Q_CAP..1
R 2
(-5000 3350);
FORCEPROP 1 LAST LOCATION C2194
J 2
(-4775 3475);
DISPLAY 0.787234 (-4775 3475);
FORCEPROP 0 LAST $SEC 1
J 0
(-4900 3500);
DISPLAY 0.680851 (-4900 3500);
PAINT MONO (-4900 3500);
DISPLAY INVISIBLE (-4900 3500);
FORCEPROP 0 LAST CDS_SEC 1
J 0
(-4900 3500);
DISPLAY 1.021277 (-4900 3500);
DISPLAY INVISIBLE (-4900 3500);
FORCEPROP 1 LASTPIN (-5000 3450) $PN 1
J 2
(-5010 3430);
DISPLAY 0.787234 (-5010 3430);
PAINT MONO (-5010 3430);
FORCEPROP 1 LASTPIN (-5000 3250) $PN 2
J 2
(-5010 3230);
DISPLAY 0.787234 (-5010 3230);
PAINT MONO (-5010 3230);
FORCEPROP 0 LAST ROOM ADC_TI_BOM1
J 0
(-4950 3125);
DISPLAY 0.680851 (-4950 3125);
PAINT RED (-4950 3125);
FORCEPROP 1 LAST TOLERANCE 10%
J 2
(-4850 3325);
DISPLAY 0.510638 (-4850 3325);
FORCEPROP 1 LAST MATERIAL X7R
J 2
(-4850 3275);
DISPLAY 0.510638 (-4850 3275);
PAINT RED (-4850 3275);
FORCEPROP 1 LAST VOLTAGE 25V
J 2
(-4850 3375);
DISPLAY 0.510638 (-4850 3375);
FORCEPROP 1 LAST PACK_TYPE 0402
J 2
(-4825 3175);
DISPLAY 0.510638 (-4825 3175);
FORCEPROP 1 LAST VALUE 0.1UF
J 2
(-4825 3425);
DISPLAY 0.510638 (-4825 3425);
FORCEPROP 2 LAST CDS_LIB pure_quanta
J 0
(-5000 3350);
DISPLAY INVISIBLE (-5000 3350);
FORCEPROP 1 LAST PATH I76
J 2
(-5050 3500);
DISPLAY 0.978723 (-5050 3500);
PAINT WHITE (-5050 3500);
DISPLAY INVISIBLE (-5050 3500);
FORCEPROP 1 LAST PART_NUMBER CH4104K1B00
J 2
(-4700 3225);
DISPLAY 0.510638 (-4700 3225);
DISPLAY INVISIBLE (-4700 3225);
FORCEADD UNIVERSAL_GND..1
(-4975 3675);
FORCEPROP 3 LASTPIN (-4975 3725) SIG_NAME GND\g
J 0
(-4965 3735);
DISPLAY 0.659574 (-4965 3735);
PAINT MONO (-4965 3735);
DISPLAY INVISIBLE (-4965 3735);
FORCEPROP 2 LAST CDS_LIB pure_quanta_power
J 0
(-4975 3675);
DISPLAY INVISIBLE (-4975 3675);
FORCEPROP 1 LAST HDL_POWER GND
J 1
(-4950 3600);
DISPLAY 0.872340 (-4950 3600);
PAINT GREEN (-4950 3600);
DISPLAY INVISIBLE (-4950 3600);
FORCEPROP 1 LAST PATH I77
J 0
(-4900 3675);
DISPLAY 0.872340 (-4900 3675);
PAINT AQUA (-4900 3675);
DISPLAY INVISIBLE (-4900 3675);
FORCEADD Q_CAP..1
(-4975 3875);
FORCEPROP 1 LAST LOCATION C35
J 0
(-4925 3975);
DISPLAY 0.510638 (-4925 3975);
FORCEPROP 2 LAST $SEC 1
J 0
(-4925 4075);
DISPLAY 0.680851 (-4925 4075);
PAINT MONO (-4925 4075);
DISPLAY INVISIBLE (-4925 4075);
FORCEPROP 0 LAST CDS_SEC 1
J 0
(-4925 4050);
DISPLAY 1.021277 (-4925 4050);
DISPLAY INVISIBLE (-4925 4050);
FORCEPROP 1 LASTPIN (-4975 3975) $PN 1
J 0
(-4965 3955);
DISPLAY 0.787234 (-4965 3955);
PAINT MONO (-4965 3955);
FORCEPROP 1 LASTPIN (-4975 3775) $PN 2
J 0
(-4965 3755);
DISPLAY 0.787234 (-4965 3755);
PAINT MONO (-4965 3755);
FORCEPROP 1 LAST PACK_TYPE 0402
J 0
(-4925 3675);
DISPLAY 0.510638 (-4925 3675);
FORCEPROP 0 LAST ROOM ADC_MAM_BOM2
J 0
(-4925 3625);
DISPLAY 0.553191 (-4925 3625);
PAINT RED (-4925 3625);
FORCEPROP 1 LAST MATERIAL EMPTY
J 0
(-4925 3775);
DISPLAY 0.510638 (-4925 3775);
FORCEPROP 1 LAST VALUE 100PF
J 0
(-4925 3925);
DISPLAY 0.510638 (-4925 3925);
FORCEPROP 1 LAST VOLTAGE 50V
J 0
(-4925 3875);
DISPLAY 0.510638 (-4925 3875);
FORCEPROP 1 LAST TOLERANCE 5%
J 0
(-4925 3825);
DISPLAY 0.510638 (-4925 3825);
FORCEPROP 2 LAST CDS_LIB pure_quanta
J 0
(-4975 3875);
DISPLAY INVISIBLE (-4975 3875);
FORCEPROP 1 LAST PATH I78
J 0
(-4925 4025);
DISPLAY 0.978723 (-4925 4025);
PAINT WHITE (-4925 4025);
DISPLAY INVISIBLE (-4925 4025);
FORCEPROP 1 LAST PART_NUMBER CH11006JB18
J 0
(-4925 3725);
DISPLAY 0.510638 (-4925 3725);
DISPLAY INVISIBLE (-4925 3725);
FORCEADD Q_RES..1
(-5700 3875);
FORCEPROP 1 LAST LOCATION R3940
J 0
(-5875 3875);
DISPLAY 0.510638 (-5875 3875);
FORCEPROP 0 LAST $SEC 1
J 0
(-5825 3925);
DISPLAY 0.680851 (-5825 3925);
PAINT MONO (-5825 3925);
DISPLAY INVISIBLE (-5825 3925);
FORCEPROP 0 LAST CDS_SEC 1
J 0
(-5825 3925);
DISPLAY 1.021277 (-5825 3925);
DISPLAY INVISIBLE (-5825 3925);
FORCEPROP 1 LASTPIN (-5800 3875) $PN 1
J 0
(-5788 3887);
DISPLAY 0.787234 (-5788 3887);
PAINT MONO (-5788 3887);
FORCEPROP 1 LASTPIN (-5600 3875) $PN 2
J 0
(-5638 3887);
DISPLAY 0.787234 (-5638 3887);
PAINT MONO (-5638 3887);
FORCEPROP 1 LAST TOLERANCE 5%
J 0
(-5525 3875);
DISPLAY 0.404255 (-5525 3875);
FORCEPROP 1 LAST MATERIAL EMPTY
J 0
(-5475 3875);
DISPLAY 0.404255 (-5475 3875);
PAINT RED (-5475 3875);
FORCEPROP 1 LAST VALUE 0
J 2
(-5550 3875);
DISPLAY 0.404255 (-5550 3875);
FORCEPROP 0 LAST ROOM ADC_MAM_BOM2
J 0
(-5850 3825);
DISPLAY 0.553191 (-5850 3825);
PAINT RED (-5850 3825);
FORCEPROP 2 LAST CDS_LIB pure_quanta
J 0
(-5700 3875);
DISPLAY INVISIBLE (-5700 3875);
FORCEPROP 1 LAST WATTAGE 1/16W
J 2
(-5600 3800);
DISPLAY 0.319149 (-5600 3800);
DISPLAY INVISIBLE (-5600 3800);
FORCEPROP 1 LAST PACK_TYPE 0402LF
J 0
(-5450 3875);
DISPLAY 0.510638 (-5450 3875);
DISPLAY INVISIBLE (-5450 3875);
FORCEPROP 1 LAST PATH I79
J 0
(-5750 4025);
DISPLAY 0.978723 (-5750 4025);
PAINT WHITE (-5750 4025);
DISPLAY INVISIBLE (-5750 4025);
FORCEPROP 1 LAST PART_NUMBER CS00002JB13
J 0
(-5775 3825);
DISPLAY 0.319149 (-5775 3825);
DISPLAY INVISIBLE (-5775 3825);
FORCEADD Q_RES..2
(-8375 1325);
FORCEPROP 1 LAST LOCATION R4567
J 0
(-8330 1450);
DISPLAY 0.638298 (-8330 1450);
FORCEPROP 0 LAST $SEC 1
J 0
(-8325 1500);
DISPLAY 0.680851 (-8325 1500);
PAINT MONO (-8325 1500);
DISPLAY INVISIBLE (-8325 1500);
FORCEPROP 0 LAST CDS_SEC 1
J 0
(-8325 1500);
DISPLAY 1.021277 (-8325 1500);
DISPLAY INVISIBLE (-8325 1500);
FORCEPROP 1 LASTPIN (-8375 1425) $PN 1
J 0
(-8370 1387);
DISPLAY 0.787234 (-8370 1387);
PAINT MONO (-8370 1387);
FORCEPROP 1 LASTPIN (-8375 1225) $PN 2
J 0
(-8370 1235);
DISPLAY 0.787234 (-8370 1235);
PAINT MONO (-8370 1235);
FORCEPROP 1 LAST TOLERANCE 1%
J 0
(-8330 1350);
DISPLAY 0.638298 (-8330 1350);
FORCEPROP 1 LAST VALUE 5.11K
J 0
(-8330 1400);
DISPLAY 0.638298 (-8330 1400);
FORCEPROP 1 LAST PACK_TYPE 0402LF
J 0
(-8335 1150);
DISPLAY 0.638298 (-8335 1150);
FORCEPROP 1 LAST MATERIAL CHIP
J 0
(-8335 1250);
DISPLAY 0.638298 (-8335 1250);
FORCEPROP 1 LAST WATTAGE 1/16W
J 0
(-8335 1300);
DISPLAY 0.638298 (-8335 1300);
FORCEPROP 2 LAST CDS_LIB pure_quanta
J 0
(-8375 1325);
DISPLAY INVISIBLE (-8375 1325);
FORCEPROP 1 LAST PATH I8
J 0
(-8325 1500);
DISPLAY 0.978723 (-8325 1500);
PAINT WHITE (-8325 1500);
DISPLAY INVISIBLE (-8325 1500);
FORCEPROP 1 LAST PART_NUMBER CS25112FB04
J 0
(-8335 1200);
DISPLAY 0.638298 (-8335 1200);
DISPLAY INVISIBLE (-8335 1200);
FORCEADD Q_RES..1
(-5700 4025);
FORCEPROP 1 LAST LOCATION R3939
J 0
(-5875 4025);
DISPLAY 0.510638 (-5875 4025);
FORCEPROP 0 LAST $SEC 1
J 0
(-5825 4075);
DISPLAY 0.680851 (-5825 4075);
PAINT MONO (-5825 4075);
DISPLAY INVISIBLE (-5825 4075);
FORCEPROP 0 LAST CDS_SEC 1
J 0
(-5825 4075);
DISPLAY 1.021277 (-5825 4075);
DISPLAY INVISIBLE (-5825 4075);
FORCEPROP 1 LASTPIN (-5800 4025) $PN 1
J 0
(-5788 4037);
DISPLAY 0.787234 (-5788 4037);
PAINT MONO (-5788 4037);
FORCEPROP 1 LASTPIN (-5600 4025) $PN 2
J 0
(-5638 4037);
DISPLAY 0.787234 (-5638 4037);
PAINT MONO (-5638 4037);
FORCEPROP 1 LAST VALUE 0
J 2
(-5550 4025);
DISPLAY 0.404255 (-5550 4025);
FORCEPROP 1 LAST MATERIAL EMPTY
J 0
(-5475 4025);
DISPLAY 0.404255 (-5475 4025);
PAINT RED (-5475 4025);
FORCEPROP 1 LAST TOLERANCE 5%
J 0
(-5525 4025);
DISPLAY 0.404255 (-5525 4025);
FORCEPROP 1 LAST PACK_TYPE 0402LF
J 0
(-5450 4025);
DISPLAY 0.510638 (-5450 4025);
DISPLAY INVISIBLE (-5450 4025);
FORCEPROP 1 LAST WATTAGE 1/16W
J 2
(-5600 3950);
DISPLAY 0.319149 (-5600 3950);
DISPLAY INVISIBLE (-5600 3950);
FORCEPROP 2 LAST CDS_LIB pure_quanta
J 0
(-5700 4025);
DISPLAY INVISIBLE (-5700 4025);
FORCEPROP 1 LAST PATH I80
J 0
(-5750 4175);
DISPLAY 0.978723 (-5750 4175);
PAINT WHITE (-5750 4175);
DISPLAY INVISIBLE (-5750 4175);
FORCEPROP 1 LAST PART_NUMBER CS00002JB13
J 0
(-5775 3975);
DISPLAY 0.319149 (-5775 3975);
DISPLAY INVISIBLE (-5775 3975);
FORCEADD Q_RES..1
(-5675 4375);
FORCEPROP 1 LAST LOCATION R3862
J 0
(-5850 4375);
DISPLAY 0.510638 (-5850 4375);
FORCEPROP 0 LAST $SEC 1
J 0
(-5800 4425);
DISPLAY 0.680851 (-5800 4425);
PAINT MONO (-5800 4425);
DISPLAY INVISIBLE (-5800 4425);
FORCEPROP 0 LAST CDS_SEC 1
J 0
(-5800 4425);
DISPLAY 1.021277 (-5800 4425);
DISPLAY INVISIBLE (-5800 4425);
FORCEPROP 1 LASTPIN (-5775 4375) $PN 1
J 0
(-5763 4387);
DISPLAY 0.787234 (-5763 4387);
PAINT MONO (-5763 4387);
FORCEPROP 1 LASTPIN (-5575 4375) $PN 2
J 0
(-5613 4387);
DISPLAY 0.787234 (-5613 4387);
PAINT MONO (-5613 4387);
FORCEPROP 1 LAST VALUE 0
J 2
(-5525 4375);
DISPLAY 0.404255 (-5525 4375);
FORCEPROP 1 LAST TOLERANCE 5%
J 0
(-5500 4375);
DISPLAY 0.404255 (-5500 4375);
FORCEPROP 1 LAST MATERIAL EMPTY
J 0
(-5450 4375);
DISPLAY 0.404255 (-5450 4375);
PAINT RED (-5450 4375);
FORCEPROP 0 LAST ROOM ADC_TI_BOM3
J 0
(-5800 4325);
DISPLAY 0.680851 (-5800 4325);
PAINT RED (-5800 4325);
FORCEPROP 2 LAST CDS_LIB pure_quanta
J 0
(-5675 4375);
DISPLAY INVISIBLE (-5675 4375);
FORCEPROP 1 LAST WATTAGE 1/16W
J 2
(-5575 4300);
DISPLAY 0.319149 (-5575 4300);
DISPLAY INVISIBLE (-5575 4300);
FORCEPROP 1 LAST PACK_TYPE 0402LF
J 0
(-5425 4375);
DISPLAY 0.510638 (-5425 4375);
DISPLAY INVISIBLE (-5425 4375);
FORCEPROP 1 LAST PATH I81
J 0
(-5725 4525);
DISPLAY 0.978723 (-5725 4525);
PAINT WHITE (-5725 4525);
DISPLAY INVISIBLE (-5725 4525);
FORCEPROP 1 LAST PART_NUMBER CS00002JB13
J 0
(-5750 4325);
DISPLAY 0.319149 (-5750 4325);
DISPLAY INVISIBLE (-5750 4325);
FORCEADD Q_RES..1
(-5675 4525);
FORCEPROP 1 LAST LOCATION R3861
J 0
(-5850 4525);
DISPLAY 0.510638 (-5850 4525);
FORCEPROP 0 LAST $SEC 1
J 0
(-5800 4575);
DISPLAY 0.680851 (-5800 4575);
PAINT MONO (-5800 4575);
DISPLAY INVISIBLE (-5800 4575);
FORCEPROP 0 LAST CDS_SEC 1
J 0
(-5800 4575);
DISPLAY 1.021277 (-5800 4575);
DISPLAY INVISIBLE (-5800 4575);
FORCEPROP 1 LASTPIN (-5775 4525) $PN 1
J 0
(-5763 4537);
DISPLAY 0.787234 (-5763 4537);
PAINT MONO (-5763 4537);
FORCEPROP 1 LASTPIN (-5575 4525) $PN 2
J 0
(-5613 4537);
DISPLAY 0.787234 (-5613 4537);
PAINT MONO (-5613 4537);
FORCEPROP 0 LAST ROOM ADC_TI_BOM1
J 0
(-5775 4600);
DISPLAY 0.553191 (-5775 4600);
PAINT RED (-5775 4600);
FORCEPROP 1 LAST TOLERANCE 5%
J 0
(-5500 4525);
DISPLAY 0.404255 (-5500 4525);
FORCEPROP 1 LAST VALUE 0
J 2
(-5525 4525);
DISPLAY 0.404255 (-5525 4525);
FORCEPROP 1 LAST MATERIAL CHIP
J 0
(-5450 4525);
DISPLAY 0.404255 (-5450 4525);
FORCEPROP 1 LAST PACK_TYPE 0402LF
J 0
(-5425 4525);
DISPLAY 0.510638 (-5425 4525);
DISPLAY INVISIBLE (-5425 4525);
FORCEPROP 1 LAST WATTAGE 1/16W
J 2
(-5575 4450);
DISPLAY 0.319149 (-5575 4450);
DISPLAY INVISIBLE (-5575 4450);
FORCEPROP 2 LAST CDS_LIB pure_quanta
J 0
(-5675 4525);
DISPLAY INVISIBLE (-5675 4525);
FORCEPROP 1 LAST PATH I82
J 0
(-5725 4675);
DISPLAY 0.978723 (-5725 4675);
PAINT WHITE (-5725 4675);
DISPLAY INVISIBLE (-5725 4675);
FORCEPROP 1 LAST PART_NUMBER CS00002JB13
J 0
(-5750 4475);
DISPLAY 0.319149 (-5750 4475);
DISPLAY INVISIBLE (-5750 4475);
FORCEADD Q_RES..1
(-5675 4875);
FORCEPROP 1 LAST LOCATION R3860
J 0
(-5850 4875);
DISPLAY 0.510638 (-5850 4875);
FORCEPROP 0 LAST $SEC 1
J 0
(-5800 4925);
DISPLAY 0.680851 (-5800 4925);
PAINT MONO (-5800 4925);
DISPLAY INVISIBLE (-5800 4925);
FORCEPROP 0 LAST CDS_SEC 1
J 0
(-5800 4925);
DISPLAY 1.021277 (-5800 4925);
DISPLAY INVISIBLE (-5800 4925);
FORCEPROP 1 LASTPIN (-5775 4875) $PN 1
J 0
(-5763 4887);
DISPLAY 0.787234 (-5763 4887);
PAINT MONO (-5763 4887);
FORCEPROP 1 LASTPIN (-5575 4875) $PN 2
J 0
(-5613 4887);
DISPLAY 0.787234 (-5613 4887);
PAINT MONO (-5613 4887);
FORCEPROP 1 LAST MATERIAL EMPTY
J 0
(-5450 4875);
DISPLAY 0.404255 (-5450 4875);
PAINT RED (-5450 4875);
FORCEPROP 1 LAST TOLERANCE 5%
J 0
(-5500 4875);
DISPLAY 0.404255 (-5500 4875);
FORCEPROP 1 LAST VALUE 0
J 2
(-5525 4875);
DISPLAY 0.404255 (-5525 4875);
FORCEPROP 0 LAST ROOM ADC_MAM_BOM2
J 0
(-5800 4825);
DISPLAY 0.553191 (-5800 4825);
PAINT RED (-5800 4825);
FORCEPROP 1 LAST PACK_TYPE 0402LF
J 0
(-5425 4875);
DISPLAY 0.510638 (-5425 4875);
DISPLAY INVISIBLE (-5425 4875);
FORCEPROP 1 LAST WATTAGE 1/16W
J 2
(-5575 4800);
DISPLAY 0.319149 (-5575 4800);
DISPLAY INVISIBLE (-5575 4800);
FORCEPROP 2 LAST CDS_LIB pure_quanta
J 0
(-5675 4875);
DISPLAY INVISIBLE (-5675 4875);
FORCEPROP 1 LAST PATH I83
J 0
(-5725 5025);
DISPLAY 0.978723 (-5725 5025);
PAINT WHITE (-5725 5025);
DISPLAY INVISIBLE (-5725 5025);
FORCEPROP 1 LAST PART_NUMBER CS00002JB13
J 0
(-5750 4825);
DISPLAY 0.319149 (-5750 4825);
DISPLAY INVISIBLE (-5750 4825);
FORCEADD Q_CAP..1
R 2
(-4975 4350);
FORCEPROP 1 LAST LOCATION C33
J 2
(-4750 4475);
DISPLAY 0.787234 (-4750 4475);
FORCEPROP 0 LAST $SEC 1
J 0
(-4875 4500);
DISPLAY 0.680851 (-4875 4500);
PAINT MONO (-4875 4500);
DISPLAY INVISIBLE (-4875 4500);
FORCEPROP 0 LAST CDS_SEC 1
J 0
(-4875 4500);
DISPLAY 1.021277 (-4875 4500);
DISPLAY INVISIBLE (-4875 4500);
FORCEPROP 1 LASTPIN (-4975 4450) $PN 1
J 2
(-4985 4430);
DISPLAY 0.787234 (-4985 4430);
PAINT MONO (-4985 4430);
FORCEPROP 1 LASTPIN (-4975 4250) $PN 2
J 2
(-4985 4230);
DISPLAY 0.787234 (-4985 4230);
PAINT MONO (-4985 4230);
FORCEPROP 1 LAST VALUE 0.1UF
J 2
(-4800 4425);
DISPLAY 0.510638 (-4800 4425);
FORCEPROP 1 LAST VOLTAGE 25V
J 2
(-4825 4375);
DISPLAY 0.510638 (-4825 4375);
FORCEPROP 1 LAST TOLERANCE 10%
J 2
(-4825 4325);
DISPLAY 0.510638 (-4825 4325);
FORCEPROP 1 LAST MATERIAL X7R
J 2
(-4825 4275);
DISPLAY 0.510638 (-4825 4275);
PAINT RED (-4825 4275);
FORCEPROP 1 LAST PACK_TYPE 0402
J 2
(-4800 4175);
DISPLAY 0.510638 (-4800 4175);
FORCEPROP 0 LAST ROOM ADC_TI_BOM1
J 0
(-4925 4125);
DISPLAY 0.553191 (-4925 4125);
PAINT RED (-4925 4125);
FORCEPROP 2 LAST CDS_LIB pure_quanta
J 0
(-4975 4350);
DISPLAY INVISIBLE (-4975 4350);
FORCEPROP 1 LAST PATH I84
J 2
(-5025 4500);
DISPLAY 0.978723 (-5025 4500);
PAINT WHITE (-5025 4500);
DISPLAY INVISIBLE (-5025 4500);
FORCEPROP 1 LAST PART_NUMBER CH4104K1B00
J 2
(-4675 4225);
DISPLAY 0.510638 (-4675 4225);
DISPLAY INVISIBLE (-4675 4225);
FORCEADD UNIVERSAL_GND..1
(-4975 4175);
FORCEPROP 3 LASTPIN (-4975 4225) SIG_NAME GND\g
J 0
(-4965 4235);
DISPLAY 0.659574 (-4965 4235);
PAINT MONO (-4965 4235);
DISPLAY INVISIBLE (-4965 4235);
FORCEPROP 2 LAST CDS_LIB pure_quanta_power
J 0
(-4975 4175);
DISPLAY INVISIBLE (-4975 4175);
FORCEPROP 1 LAST HDL_POWER GND
J 1
(-4950 4100);
DISPLAY 0.872340 (-4950 4100);
PAINT GREEN (-4950 4100);
DISPLAY INVISIBLE (-4950 4100);
FORCEPROP 1 LAST PATH I85
J 0
(-4900 4175);
DISPLAY 0.872340 (-4900 4175);
PAINT AQUA (-4900 4175);
DISPLAY INVISIBLE (-4900 4175);
FORCEADD UNIVERSAL_GND..1
(-4950 4675);
FORCEPROP 3 LASTPIN (-4950 4725) SIG_NAME GND\g
J 0
(-4940 4735);
DISPLAY 0.659574 (-4940 4735);
PAINT MONO (-4940 4735);
DISPLAY INVISIBLE (-4940 4735);
FORCEPROP 2 LAST CDS_LIB pure_quanta_power
J 0
(-4950 4675);
DISPLAY INVISIBLE (-4950 4675);
FORCEPROP 1 LAST HDL_POWER GND
J 1
(-4925 4600);
DISPLAY 0.872340 (-4925 4600);
PAINT GREEN (-4925 4600);
DISPLAY INVISIBLE (-4925 4600);
FORCEPROP 1 LAST PATH I86
J 0
(-4875 4675);
DISPLAY 0.872340 (-4875 4675);
PAINT AQUA (-4875 4675);
DISPLAY INVISIBLE (-4875 4675);
FORCEADD Q_CAP..1
(-4950 4875);
FORCEPROP 1 LAST LOCATION C59
J 0
(-4900 4975);
DISPLAY 0.510638 (-4900 4975);
FORCEPROP 2 LAST $SEC 1
J 0
(-4900 5075);
DISPLAY 0.680851 (-4900 5075);
PAINT MONO (-4900 5075);
DISPLAY INVISIBLE (-4900 5075);
FORCEPROP 0 LAST CDS_SEC 1
J 0
(-4900 5050);
DISPLAY 1.021277 (-4900 5050);
DISPLAY INVISIBLE (-4900 5050);
FORCEPROP 1 LASTPIN (-4950 4975) $PN 1
J 0
(-4940 4955);
DISPLAY 0.787234 (-4940 4955);
PAINT MONO (-4940 4955);
FORCEPROP 1 LASTPIN (-4950 4775) $PN 2
J 0
(-4940 4755);
DISPLAY 0.787234 (-4940 4755);
PAINT MONO (-4940 4755);
FORCEPROP 1 LAST VOLTAGE 50V
J 0
(-4900 4875);
DISPLAY 0.510638 (-4900 4875);
FORCEPROP 1 LAST TOLERANCE 5%
J 0
(-4900 4825);
DISPLAY 0.510638 (-4900 4825);
FORCEPROP 0 LAST ROOM ADC_MAM_BOM2
J 0
(-4900 4625);
DISPLAY 0.553191 (-4900 4625);
PAINT RED (-4900 4625);
FORCEPROP 1 LAST VALUE 100PF
J 0
(-4900 4925);
DISPLAY 0.510638 (-4900 4925);
FORCEPROP 1 LAST MATERIAL EMPTY
J 0
(-4900 4775);
DISPLAY 0.510638 (-4900 4775);
FORCEPROP 1 LAST PACK_TYPE 0402
J 0
(-4900 4675);
DISPLAY 0.510638 (-4900 4675);
FORCEPROP 2 LAST CDS_LIB pure_quanta
J 0
(-4950 4875);
DISPLAY INVISIBLE (-4950 4875);
FORCEPROP 1 LAST PATH I87
J 0
(-4900 5025);
DISPLAY 0.978723 (-4900 5025);
PAINT WHITE (-4900 5025);
DISPLAY INVISIBLE (-4900 5025);
FORCEPROP 1 LAST PART_NUMBER CH11006JB18
J 0
(-4900 4725);
DISPLAY 0.510638 (-4900 4725);
DISPLAY INVISIBLE (-4900 4725);
FORCEADD UNIVERSAL_POWER..1
(-4650 2950);
FORCEPROP 3 LASTPIN (-4650 2900) SIG_NAME P3V3_AUX\g
J 0
(-4640 2910);
DISPLAY 0.659574 (-4640 2910);
PAINT MONO (-4640 2910);
DISPLAY INVISIBLE (-4640 2910);
FORCEPROP 1 LAST HDL_POWER P3V3_AUX
J 1
(-4650 3000);
DISPLAY 0.872340 (-4650 3000);
PAINT GREEN (-4650 3000);
FORCEPROP 2 LAST CDS_LIB pure_quanta_power
J 0
(-4650 2950);
DISPLAY INVISIBLE (-4650 2950);
FORCEPROP 1 LAST PATH I88
J 0
(-4600 2975);
DISPLAY 0.872340 (-4600 2975);
PAINT AQUA (-4600 2975);
DISPLAY INVISIBLE (-4600 2975);
FORCEADD OFFPAGE..2
(-4725 3525);
FORCEPROP 2 LAST $XR0 258 
J 0
(-4536 3525);
DISPLAY 0.638298 (-4536 3525);
PAINT MONO (-4536 3525);
FORCEPROP 2 LAST CDS_LIB standard
J 0
(-4725 3525);
DISPLAY INVISIBLE (-4725 3525);
FORCEPROP 1 LAST OFFPAGE TRUE
J 0
(-4400 3400);
DISPLAY 0.872340 (-4400 3400);
DISPLAY INVISIBLE (-4400 3400);
FORCEPROP 1 LAST COMMENT_BODY TRUE
J 0
(-4770 3430);
DISPLAY 0.872340 (-4770 3430);
PAINT GREEN (-4770 3430);
DISPLAY INVISIBLE (-4770 3430);
FORCEPROP 2 LAST PATH I89
J 0
(-4525 3575);
DISPLAY 0.680851 (-4525 3575);
DISPLAY INVISIBLE (-4525 3575);
FORCEADD Q_RES..1
(-8100 2050);
FORCEPROP 1 LAST LOCATION R3680
J 0
(-8300 2050);
DISPLAY 0.638298 (-8300 2050);
FORCEPROP 0 LAST $SEC 1
J 0
(-8225 2100);
DISPLAY 0.680851 (-8225 2100);
PAINT MONO (-8225 2100);
DISPLAY INVISIBLE (-8225 2100);
FORCEPROP 0 LAST CDS_SEC 1
J 0
(-8225 2100);
DISPLAY 1.021277 (-8225 2100);
DISPLAY INVISIBLE (-8225 2100);
FORCEPROP 1 LASTPIN (-8200 2050) $PN 1
J 0
(-8188 2062);
DISPLAY 0.787234 (-8188 2062);
PAINT MONO (-8188 2062);
FORCEPROP 1 LASTPIN (-8000 2050) $PN 2
J 0
(-8038 2062);
DISPLAY 0.787234 (-8038 2062);
PAINT MONO (-8038 2062);
FORCEPROP 1 LAST MATERIAL CHIP
J 0
(-7875 2050);
DISPLAY 0.404255 (-7875 2050);
PAINT RED (-7875 2050);
FORCEPROP 0 LAST ROOM ADC_TI_BOM1
J 0
(-8275 1975);
DISPLAY 0.553191 (-8275 1975);
PAINT RED (-8275 1975);
FORCEPROP 1 LAST VALUE 0
J 2
(-7950 2050);
DISPLAY 0.404255 (-7950 2050);
FORCEPROP 1 LAST TOLERANCE 5%
J 0
(-7925 2050);
DISPLAY 0.404255 (-7925 2050);
FORCEPROP 2 LAST CDS_LIB pure_quanta
J 0
(-8100 2050);
DISPLAY INVISIBLE (-8100 2050);
FORCEPROP 1 LAST WATTAGE 1/16W
J 2
(-8000 1975);
DISPLAY 0.319149 (-8000 1975);
DISPLAY INVISIBLE (-8000 1975);
FORCEPROP 1 LAST PACK_TYPE 0402LF
J 0
(-7850 2050);
DISPLAY 0.510638 (-7850 2050);
DISPLAY INVISIBLE (-7850 2050);
FORCEPROP 1 LAST PATH I9
J 0
(-8150 2200);
DISPLAY 0.978723 (-8150 2200);
PAINT WHITE (-8150 2200);
DISPLAY INVISIBLE (-8150 2200);
FORCEPROP 1 LAST PART_NUMBER CS00002JB13
J 0
(-8175 2000);
DISPLAY 0.319149 (-8175 2000);
DISPLAY INVISIBLE (-8175 2000);
FORCEADD OFFPAGE..2
(-4725 4025);
FORCEPROP 2 LAST $XR0 258 
J 0
(-4536 4025);
DISPLAY 0.638298 (-4536 4025);
PAINT MONO (-4536 4025);
FORCEPROP 2 LAST CDS_LIB standard
J 0
(-4725 4025);
DISPLAY INVISIBLE (-4725 4025);
FORCEPROP 1 LAST OFFPAGE TRUE
J 0
(-4400 3900);
DISPLAY 0.872340 (-4400 3900);
DISPLAY INVISIBLE (-4400 3900);
FORCEPROP 1 LAST COMMENT_BODY TRUE
J 0
(-4770 3930);
DISPLAY 0.872340 (-4770 3930);
PAINT GREEN (-4770 3930);
DISPLAY INVISIBLE (-4770 3930);
FORCEPROP 2 LAST PATH I90
J 0
(-4525 4075);
DISPLAY 0.680851 (-4525 4075);
DISPLAY INVISIBLE (-4525 4075);
FORCEADD OFFPAGE..2
(-4700 4525);
FORCEPROP 2 LAST $XR0 258 
J 0
(-4511 4525);
DISPLAY 0.638298 (-4511 4525);
PAINT MONO (-4511 4525);
FORCEPROP 2 LAST CDS_LIB standard
J 0
(-4700 4525);
DISPLAY INVISIBLE (-4700 4525);
FORCEPROP 1 LAST OFFPAGE TRUE
J 0
(-4375 4400);
DISPLAY 0.872340 (-4375 4400);
DISPLAY INVISIBLE (-4375 4400);
FORCEPROP 1 LAST COMMENT_BODY TRUE
J 0
(-4745 4430);
DISPLAY 0.872340 (-4745 4430);
PAINT GREEN (-4745 4430);
DISPLAY INVISIBLE (-4745 4430);
FORCEPROP 2 LAST PATH I91
J 0
(-4500 4575);
DISPLAY 0.680851 (-4500 4575);
DISPLAY INVISIBLE (-4500 4575);
FORCEADD OFFPAGE..4
R 2
(-3675 4550);
FORCEPROP 2 LAST $XR0 258 
J 0
(-3927 4550);
DISPLAY 0.638298 (-3927 4550);
PAINT MONO (-3927 4550);
FORCEPROP 2 LAST CDS_LIB standard
J 0
(-3675 4550);
DISPLAY INVISIBLE (-3675 4550);
FORCEPROP 1 LAST OFFPAGE TRUE
J 2
(-4000 4425);
DISPLAY 0.872340 (-4000 4425);
DISPLAY INVISIBLE (-4000 4425);
FORCEPROP 1 LAST COMMENT_BODY TRUE
J 2
(-3650 4450);
DISPLAY 0.872340 (-3650 4450);
PAINT GREEN (-3650 4450);
DISPLAY INVISIBLE (-3650 4450);
FORCEPROP 2 LAST PATH I92
J 0
(-3925 4600);
DISPLAY 0.680851 (-3925 4600);
DISPLAY INVISIBLE (-3925 4600);
FORCEADD OFFPAGE..4
R 2
(-3675 4650);
FORCEPROP 2 LAST $XR0 258 
J 0
(-3927 4650);
DISPLAY 0.638298 (-3927 4650);
PAINT MONO (-3927 4650);
FORCEPROP 2 LAST CDS_LIB standard
J 0
(-3675 4650);
DISPLAY INVISIBLE (-3675 4650);
FORCEPROP 1 LAST OFFPAGE TRUE
J 2
(-4000 4525);
DISPLAY 0.872340 (-4000 4525);
DISPLAY INVISIBLE (-4000 4525);
FORCEPROP 1 LAST COMMENT_BODY TRUE
J 2
(-3650 4550);
DISPLAY 0.872340 (-3650 4550);
PAINT GREEN (-3650 4550);
DISPLAY INVISIBLE (-3650 4550);
FORCEPROP 2 LAST PATH I93
J 0
(-3925 4700);
DISPLAY 0.680851 (-3925 4700);
DISPLAY INVISIBLE (-3925 4700);
FORCEADD OFFPAGE..4
R 2
(-3675 4850);
FORCEPROP 2 LAST $XR0 258 
J 0
(-3927 4850);
DISPLAY 0.638298 (-3927 4850);
PAINT MONO (-3927 4850);
FORCEPROP 2 LAST CDS_LIB standard
J 0
(-3675 4850);
DISPLAY INVISIBLE (-3675 4850);
FORCEPROP 1 LAST OFFPAGE TRUE
J 2
(-4000 4725);
DISPLAY 0.872340 (-4000 4725);
DISPLAY INVISIBLE (-4000 4725);
FORCEPROP 1 LAST COMMENT_BODY TRUE
J 2
(-3650 4750);
DISPLAY 0.872340 (-3650 4750);
PAINT GREEN (-3650 4750);
DISPLAY INVISIBLE (-3650 4750);
FORCEPROP 2 LAST PATH I94
J 0
(-3925 4900);
DISPLAY 0.680851 (-3925 4900);
DISPLAY INVISIBLE (-3925 4900);
FORCEADD OFFPAGE..4
R 2
(-3675 4750);
FORCEPROP 2 LAST $XR0 258 
J 0
(-3927 4750);
DISPLAY 0.638298 (-3927 4750);
PAINT MONO (-3927 4750);
FORCEPROP 2 LAST CDS_LIB standard
J 0
(-3675 4750);
DISPLAY INVISIBLE (-3675 4750);
FORCEPROP 1 LAST OFFPAGE TRUE
J 2
(-4000 4625);
DISPLAY 0.872340 (-4000 4625);
DISPLAY INVISIBLE (-4000 4625);
FORCEPROP 1 LAST COMMENT_BODY TRUE
J 2
(-3650 4650);
DISPLAY 0.872340 (-3650 4650);
PAINT GREEN (-3650 4650);
DISPLAY INVISIBLE (-3650 4650);
FORCEPROP 2 LAST PATH I95
J 0
(-3925 4800);
DISPLAY 0.680851 (-3925 4800);
DISPLAY INVISIBLE (-3925 4800);
FORCEADD UNIVERSAL_GND..1
(-7825 5300);
FORCEPROP 3 LASTPIN (-7825 5350) SIG_NAME GND\g
J 0
(-7815 5360);
DISPLAY 0.659574 (-7815 5360);
PAINT MONO (-7815 5360);
DISPLAY INVISIBLE (-7815 5360);
FORCEPROP 2 LAST CDS_LIB pure_quanta_power
J 0
(-7825 5300);
DISPLAY INVISIBLE (-7825 5300);
FORCEPROP 1 LAST HDL_POWER GND
J 1
(-7800 5225);
DISPLAY 0.872340 (-7800 5225);
PAINT GREEN (-7800 5225);
DISPLAY INVISIBLE (-7800 5225);
FORCEPROP 1 LAST PATH I96
J 0
(-7750 5300);
DISPLAY 0.872340 (-7750 5300);
PAINT AQUA (-7750 5300);
DISPLAY INVISIBLE (-7750 5300);
FORCEADD UNIVERSAL_GND..1
(-7475 5300);
FORCEPROP 3 LASTPIN (-7475 5350) SIG_NAME GND\g
J 0
(-7465 5360);
DISPLAY 0.659574 (-7465 5360);
PAINT MONO (-7465 5360);
DISPLAY INVISIBLE (-7465 5360);
FORCEPROP 2 LAST CDS_LIB pure_quanta_power
J 0
(-7475 5300);
DISPLAY INVISIBLE (-7475 5300);
FORCEPROP 1 LAST HDL_POWER GND
J 1
(-7450 5225);
DISPLAY 0.872340 (-7450 5225);
PAINT GREEN (-7450 5225);
DISPLAY INVISIBLE (-7450 5225);
FORCEPROP 1 LAST PATH I97
J 0
(-7400 5300);
DISPLAY 0.872340 (-7400 5300);
PAINT AQUA (-7400 5300);
DISPLAY INVISIBLE (-7400 5300);
FORCEADD Q_CAP..1
R 2
(-7825 5575);
FORCEPROP 1 LAST LOCATION C2047
J 2
(-7650 5675);
DISPLAY 0.638298 (-7650 5675);
FORCEPROP 0 LAST $SEC 1
J 0
(-7725 5725);
DISPLAY 0.680851 (-7725 5725);
PAINT MONO (-7725 5725);
DISPLAY INVISIBLE (-7725 5725);
FORCEPROP 0 LAST CDS_SEC 1
J 0
(-7725 5725);
DISPLAY 1.021277 (-7725 5725);
DISPLAY INVISIBLE (-7725 5725);
FORCEPROP 1 LASTPIN (-7825 5675) $PN 1
J 2
(-7835 5655);
DISPLAY 0.787234 (-7835 5655);
PAINT MONO (-7835 5655);
FORCEPROP 1 LASTPIN (-7825 5475) $PN 2
J 2
(-7835 5455);
DISPLAY 0.787234 (-7835 5455);
PAINT MONO (-7835 5455);
FORCEPROP 1 LAST PACK_TYPE 0402
J 2
(-7650 5400);
DISPLAY 0.510638 (-7650 5400);
FORCEPROP 1 LAST MATERIAL X7R
J 2
(-7675 5500);
DISPLAY 0.510638 (-7675 5500);
PAINT RED (-7675 5500);
FORCEPROP 1 LAST TOLERANCE 10%
J 2
(-7675 5550);
DISPLAY 0.510638 (-7675 5550);
FORCEPROP 1 LAST VOLTAGE 25V
J 2
(-7675 5600);
DISPLAY 0.510638 (-7675 5600);
FORCEPROP 1 LAST VALUE 0.1UF
J 2
(-7650 5650);
DISPLAY 0.510638 (-7650 5650);
FORCEPROP 0 LAST ROOM ADC_TI_BOM1
J 0
(-7800 5350);
DISPLAY 0.553191 (-7800 5350);
PAINT RED (-7800 5350);
FORCEPROP 2 LAST CDS_LIB pure_quanta
J 0
(-7825 5575);
DISPLAY INVISIBLE (-7825 5575);
FORCEPROP 1 LAST PATH I98
J 2
(-7875 5725);
DISPLAY 0.978723 (-7875 5725);
PAINT WHITE (-7875 5725);
DISPLAY INVISIBLE (-7875 5725);
FORCEPROP 1 LAST PART_NUMBER CH4104K1B00
J 2
(-7525 5450);
DISPLAY 0.510638 (-7525 5450);
DISPLAY INVISIBLE (-7525 5450);
FORCEADD Q_CAP..1
(-7475 5575);
FORCEPROP 1 LAST LOCATION C2042
J 0
(-7425 5675);
DISPLAY 0.510638 (-7425 5675);
FORCEPROP 2 LAST $SEC 1
J 0
(-7425 5775);
DISPLAY 0.680851 (-7425 5775);
PAINT MONO (-7425 5775);
DISPLAY INVISIBLE (-7425 5775);
FORCEPROP 0 LAST CDS_SEC 1
J 0
(-7425 5750);
DISPLAY 1.021277 (-7425 5750);
DISPLAY INVISIBLE (-7425 5750);
FORCEPROP 1 LASTPIN (-7475 5675) $PN 1
J 0
(-7465 5655);
DISPLAY 0.787234 (-7465 5655);
PAINT MONO (-7465 5655);
FORCEPROP 1 LASTPIN (-7475 5475) $PN 2
J 0
(-7465 5455);
DISPLAY 0.787234 (-7465 5455);
PAINT MONO (-7465 5455);
FORCEPROP 1 LAST TOLERANCE 5%
J 0
(-7425 5525);
DISPLAY 0.510638 (-7425 5525);
FORCEPROP 1 LAST VALUE 100PF
J 0
(-7425 5625);
DISPLAY 0.510638 (-7425 5625);
FORCEPROP 1 LAST MATERIAL EMPTY
J 0
(-7425 5475);
DISPLAY 0.510638 (-7425 5475);
FORCEPROP 1 LAST VOLTAGE 50V
J 0
(-7425 5575);
DISPLAY 0.510638 (-7425 5575);
FORCEPROP 1 LAST PACK_TYPE 0402
J 0
(-7425 5375);
DISPLAY 0.510638 (-7425 5375);
FORCEPROP 0 LAST ROOM ADC_MAM_BOM2
J 0
(-7425 5325);
DISPLAY 0.553191 (-7425 5325);
PAINT RED (-7425 5325);
FORCEPROP 2 LAST CDS_LIB pure_quanta
J 0
(-7475 5575);
DISPLAY INVISIBLE (-7475 5575);
FORCEPROP 1 LAST PATH I99
J 0
(-7425 5725);
DISPLAY 0.978723 (-7425 5725);
PAINT WHITE (-7425 5725);
DISPLAY INVISIBLE (-7425 5725);
FORCEPROP 1 LAST PART_NUMBER CH11006JB18
J 0
(-7425 5425);
DISPLAY 0.510638 (-7425 5425);
DISPLAY INVISIBLE (-7425 5425);
FORCEADD CAD_NOTE..1
(-3525 3500);
FORCEPROP 0 LAST S1 POP U269, AND DE-POP U193 WHICH IS 2ND SOLUTION
J 0
(-3675 3350);
DISPLAY 1.021277 (-3675 3350);
PAINT SKYBLUE (-3675 3350);
FORCEPROP 2 LAST CDS_LIB pure_quanta_power
J 0
(-3525 3500);
DISPLAY INVISIBLE (-3525 3500);
FORCEPROP 1 LAST COMMENT_BODY TRUE
J 0
(-3500 3600);
DISPLAY 0.978723 (-3500 3600);
DISPLAY INVISIBLE (-3500 3600);
FORCEADD DNS..2
(-8075 2200);
PAINT RED (-8075 2200);
FORCEPROP 2 LAST CDS_LIB mstr_misc
J 0
(-8075 2200);
DISPLAY INVISIBLE (-8075 2200);
FORCEPROP 1 LAST COMMENT_BODY TRUE
J 0
(-8075 2200);
DISPLAY INVISIBLE (-8075 2200);
FORCEADD DNS..2
(-5650 4375);
PAINT RED (-5650 4375);
FORCEPROP 2 LAST CDS_LIB mstr_misc
J 0
(-5650 4375);
DISPLAY INVISIBLE (-5650 4375);
FORCEPROP 1 LAST COMMENT_BODY TRUE
J 0
(-5650 4375);
DISPLAY INVISIBLE (-5650 4375);
FORCEADD DNS..2
(-7400 1300);
PAINT RED (-7400 1300);
FORCEPROP 2 LAST CDS_LIB mstr_misc
J 0
(-7400 1300);
DISPLAY INVISIBLE (-7400 1300);
FORCEPROP 1 LAST COMMENT_BODY TRUE
J 0
(-7400 1300);
DISPLAY INVISIBLE (-7400 1300);
FORCEADD DNS..2
(-5675 4025);
PAINT RED (-5675 4025);
FORCEPROP 2 LAST CDS_LIB mstr_misc
J 0
(-5675 4025);
DISPLAY INVISIBLE (-5675 4025);
FORCEPROP 1 LAST COMMENT_BODY TRUE
J 0
(-5675 4025);
DISPLAY INVISIBLE (-5675 4025);
FORCEADD DNS..2
(-3475 2475);
PAINT RED (-3475 2475);
FORCEPROP 2 LAST CDS_LIB mstr_misc
J 0
(-3475 2475);
DISPLAY INVISIBLE (-3475 2475);
FORCEPROP 1 LAST COMMENT_BODY TRUE
J 0
(-3475 2475);
DISPLAY INVISIBLE (-3475 2475);
FORCEADD DNS..2
(-4300 1300);
PAINT RED (-4300 1300);
FORCEPROP 2 LAST CDS_LIB mstr_misc
J 0
(-4300 1300);
PAINT MONO (-4300 1300);
DISPLAY INVISIBLE (-4300 1300);
FORCEPROP 1 LAST COMMENT_BODY TRUE
J 0
(-4300 1300);
DISPLAY INVISIBLE (-4300 1300);
FORCEADD DNS..2
(-7550 3075);
PAINT RED (-7550 3075);
FORCEPROP 2 LAST CDS_LIB mstr_misc
J 0
(-7550 3075);
DISPLAY INVISIBLE (-7550 3075);
FORCEPROP 1 LAST COMMENT_BODY TRUE
J 0
(-7550 3075);
DISPLAY INVISIBLE (-7550 3075);
FORCEADD DNS..2
(-7450 5575);
PAINT RED (-7450 5575);
FORCEPROP 2 LAST CDS_LIB mstr_misc
J 0
(-7450 5575);
DISPLAY INVISIBLE (-7450 5575);
FORCEPROP 1 LAST COMMENT_BODY TRUE
J 0
(-7450 5575);
DISPLAY INVISIBLE (-7450 5575);
FORCEADD DNS..2
(-4550 1300);
PAINT RED (-4550 1300);
FORCEPROP 2 LAST CDS_LIB mstr_misc
J 0
(-4550 1300);
PAINT MONO (-4550 1300);
DISPLAY INVISIBLE (-4550 1300);
FORCEPROP 1 LAST COMMENT_BODY TRUE
J 0
(-4550 1300);
DISPLAY INVISIBLE (-4550 1300);
FORCEADD DNS..2
(-2400 4875);
PAINT RED (-2400 4875);
FORCEPROP 2 LAST CDS_LIB mstr_misc
J 0
(-2400 4875);
DISPLAY INVISIBLE (-2400 4875);
FORCEPROP 1 LAST COMMENT_BODY TRUE
J 0
(-2400 4875);
DISPLAY INVISIBLE (-2400 4875);
FORCEADD DNS..2
(-5625 6000);
PAINT RED (-5625 6000);
FORCEPROP 2 LAST CDS_LIB mstr_misc
J 0
(-5625 6000);
DISPLAY INVISIBLE (-5625 6000);
FORCEPROP 1 LAST COMMENT_BODY TRUE
J 0
(-5625 6000);
DISPLAY INVISIBLE (-5625 6000);
FORCEADD DNS..2
(-2375 3675);
PAINT RED (-2375 3675);
FORCEPROP 2 LAST CDS_LIB mstr_misc
J 0
(-2375 3675);
DISPLAY INVISIBLE (-2375 3675);
FORCEPROP 1 LAST COMMENT_BODY TRUE
J 0
(-2375 3675);
DISPLAY INVISIBLE (-2375 3675);
FORCEADD DNS..2
(-8175 5975);
PAINT RED (-8175 5975);
FORCEPROP 2 LAST CDS_LIB mstr_misc
J 0
(-8175 5975);
DISPLAY INVISIBLE (-8175 5975);
FORCEPROP 1 LAST COMMENT_BODY TRUE
J 0
(-8175 5975);
DISPLAY INVISIBLE (-8175 5975);
FORCEADD DNS..2
(-4950 4850);
PAINT RED (-4950 4850);
FORCEPROP 2 LAST CDS_LIB mstr_misc
J 0
(-4950 4850);
DISPLAY INVISIBLE (-4950 4850);
FORCEPROP 1 LAST COMMENT_BODY TRUE
J 0
(-4950 4850);
DISPLAY INVISIBLE (-4950 4850);
FORCEADD DNS..2
(-6525 850);
PAINT RED (-6525 850);
FORCEPROP 2 LAST CDS_LIB mstr_misc
J 0
(-6525 850);
DISPLAY INVISIBLE (-6525 850);
FORCEPROP 1 LAST COMMENT_BODY TRUE
J 0
(-6525 850);
DISPLAY INVISIBLE (-6525 850);
FORCEADD DNS..2
(-5650 4875);
PAINT RED (-5650 4875);
FORCEPROP 2 LAST CDS_LIB mstr_misc
J 0
(-5650 4875);
DISPLAY INVISIBLE (-5650 4875);
FORCEPROP 1 LAST COMMENT_BODY TRUE
J 0
(-5650 4875);
DISPLAY INVISIBLE (-5650 4875);
FORCEADD DNS..2
(-5675 3875);
PAINT RED (-5675 3875);
FORCEPROP 2 LAST CDS_LIB mstr_misc
J 0
(-5675 3875);
DISPLAY INVISIBLE (-5675 3875);
FORCEPROP 1 LAST COMMENT_BODY TRUE
J 0
(-5675 3875);
DISPLAY INVISIBLE (-5675 3875);
FORCEADD DNS..2
(-7175 1775);
PAINT RED (-7175 1775);
FORCEPROP 2 LAST CDS_LIB mstr_misc
J 0
(-7175 1775);
DISPLAY INVISIBLE (-7175 1775);
FORCEPROP 1 LAST COMMENT_BODY TRUE
J 0
(-7175 1775);
DISPLAY INVISIBLE (-7175 1775);
FORCEADD DNS..2
(-7525 4225);
PAINT RED (-7525 4225);
FORCEPROP 2 LAST CDS_LIB mstr_misc
J 0
(-7525 4225);
DISPLAY INVISIBLE (-7525 4225);
FORCEPROP 1 LAST COMMENT_BODY TRUE
J 0
(-7525 4225);
DISPLAY INVISIBLE (-7525 4225);
FORCEADD DNS..2
(-3450 2000);
PAINT RED (-3450 2000);
FORCEPROP 2 LAST CDS_LIB mstr_misc
J 0
(-3450 2000);
DISPLAY INVISIBLE (-3450 2000);
FORCEPROP 1 LAST COMMENT_BODY TRUE
J 0
(-3450 2000);
DISPLAY INVISIBLE (-3450 2000);
FORCEADD DNS..2
(-5625 5850);
PAINT RED (-5625 5850);
FORCEPROP 2 LAST CDS_LIB mstr_misc
J 0
(-5625 5850);
DISPLAY INVISIBLE (-5625 5850);
FORCEPROP 1 LAST COMMENT_BODY TRUE
J 0
(-5625 5850);
DISPLAY INVISIBLE (-5625 5850);
FORCEADD QUANTA_TITLE_BLOCK_C..1
(0 0);
FORCEPROP 0 LAST CDS_CON_LAST_MODIFIED Thu Sep 14 16:12:43 2023
J 0
(-1885 15);
DISPLAY INVISIBLE (-1885 15);
FORCEPROP 1 LAST CUSTOM_TXT_CDS <CON_LAST_MODIFIED>
J 0
(-1885 15);
DISPLAY 0.978723 (-1885 15);
FORCEPROP 2 LAST CUSTOM_TXT_CDS <XR_PAGE_TITLE>
J 0
(-7890 5250);
DISPLAY 0.638298 (-7890 5250);
PAINT PINK (-7890 5250);
DISPLAY INVISIBLE (-7890 5250);
FORCEPROP 1 LAST CUSTOM_TXT_CDS <NAME_2>
J 0
(-3175 50);
FORCEPROP 1 LAST CUSTOM_TXT_CDS <NAME_1>
J 0
(-3175 175);
FORCEPROP 1 LAST CUSTOM_TXT_CDS <Q_NUMBER>
J 0
(-1403 103);
DISPLAY 1.212766 (-1403 103);
FORCEPROP 1 LAST CUSTOM_TXT_CDS <Q_PROJ>
J 0
(-2382 102);
DISPLAY 1.212766 (-2382 102);
FORCEPROP 1 LAST CUSTOM_TXT_CDS <Q_REV>
J 0
(-184 103);
DISPLAY 1.212766 (-184 103);
FORCEPROP 1 LAST CUSTOM_TXT_CDS <CON_PAGE_NUM> OF <CON_TOTAL_PAGES>
J 0
(-446 18);
DISPLAY 0.978723 (-446 18);
FORCEPROP 1 LAST Q_TITLE VOLTAGE SENSOR (1/2)
J 0
(-9366 26);
DISPLAY 2.446809 (-9366 26);
PAINT GREEN (-9366 26);
FORCEPROP 1 LAST CDS_LMAN_SYM_OUTLINE -9475,6775,100,-125
J 0
(0 0);
DISPLAY 0.468085 (0 0);
PAINT GREEN (0 0);
DISPLAY INVISIBLE (0 0);
FORCEPROP 2 LAST CDS_LIB pure_quanta
J 0
(0 0);
DISPLAY INVISIBLE (0 0);
FORCEPROP 2 LAST PAGE_BORDER TRUE
J 0
(-7890 5250);
DISPLAY 0.638298 (-7890 5250);
PAINT PINK (-7890 5250);
DISPLAY INVISIBLE (-7890 5250);
FORCEPROP 2 LAST CDS_XR_PAGE_TITLE CR-258 : @T6G_MB_LIB.T6G(SCH_1):PAGE258
J 0
(-7890 5250);
DISPLAY 0.638298 (-7890 5250);
PAINT PINK (-7890 5250);
DISPLAY INVISIBLE (-7890 5250);
FORCEPROP 1 LAST Q_DEPT BU9
J 1
(-3763 49);
DISPLAY 1.957447 (-3763 49);
PAINT GREEN (-3763 49);
DISPLAY INVISIBLE (-3763 49);
FORCEPROP 1 LAST COMMENT_BODY TRUE
J 0
(12 -13);
DISPLAY 0.978723 (12 -13);
PAINT GREEN (12 -13);
DISPLAY INVISIBLE (12 -13);
FORCEADD DNS..2
(-8250 3500);
PAINT RED (-8250 3500);
FORCEPROP 2 LAST CDS_LIB mstr_misc
J 0
(-8250 3500);
DISPLAY INVISIBLE (-8250 3500);
FORCEPROP 1 LAST COMMENT_BODY TRUE
J 0
(-8250 3500);
DISPLAY INVISIBLE (-8250 3500);
FORCEADD DNS..2
(-5625 5350);
PAINT RED (-5625 5350);
FORCEPROP 2 LAST CDS_LIB mstr_misc
J 0
(-5625 5350);
DISPLAY INVISIBLE (-5625 5350);
FORCEPROP 1 LAST COMMENT_BODY TRUE
J 0
(-5625 5350);
DISPLAY INVISIBLE (-5625 5350);
FORCEADD DNS..2
(-5650 5025);
PAINT RED (-5650 5025);
FORCEPROP 2 LAST CDS_LIB mstr_misc
J 0
(-5650 5025);
DISPLAY INVISIBLE (-5650 5025);
FORCEPROP 1 LAST COMMENT_BODY TRUE
J 0
(-5650 5025);
DISPLAY INVISIBLE (-5650 5025);
FORCEADD DNS..2
(-4975 3850);
PAINT RED (-4975 3850);
FORCEPROP 2 LAST CDS_LIB mstr_misc
J 0
(-4975 3850);
DISPLAY INVISIBLE (-4975 3850);
FORCEPROP 1 LAST COMMENT_BODY TRUE
J 0
(-4975 3850);
DISPLAY INVISIBLE (-4975 3850);
FORCEADD DNS..2
(-4925 5825);
PAINT RED (-4925 5825);
FORCEPROP 2 LAST CDS_LIB mstr_misc
J 0
(-4925 5825);
DISPLAY INVISIBLE (-4925 5825);
FORCEPROP 1 LAST COMMENT_BODY TRUE
J 0
(-4925 5825);
DISPLAY INVISIBLE (-4925 5825);
FORCEADD DNS..2
(-8250 4650);
PAINT RED (-8250 4650);
FORCEPROP 2 LAST CDS_LIB mstr_misc
J 0
(-8250 4650);
DISPLAY INVISIBLE (-8250 4650);
FORCEPROP 1 LAST COMMENT_BODY TRUE
J 0
(-8250 4650);
DISPLAY INVISIBLE (-8250 4650);
FORCEADD DNS..2
(-5675 3375);
PAINT RED (-5675 3375);
FORCEPROP 2 LAST CDS_LIB mstr_misc
J 0
(-5675 3375);
DISPLAY INVISIBLE (-5675 3375);
FORCEPROP 1 LAST COMMENT_BODY TRUE
J 0
(-5675 3375);
DISPLAY INVISIBLE (-5675 3375);
WIRE 16 -1 (-8375 850)(-8375 775);
WIRE 16 -1 (-7925 2975)(-7925 2850);
WIRE 16 -1 (-4950 5225)(-4950 5200);
WIRE 16 -1 (-4925 5750)(-4925 5700);
WIRE 16 -1 (-4200 5200)(-4200 5250);
WIRE 16 -1 (-8900 4325)(-8900 4225);
WIRE 16 -1 (-3825 5250)(-3825 5200);
WIRE 16 -1 (-3475 1900)(-3475 1725);
WIRE 16 -1 (-8900 3100)(-8900 2950);
WIRE 16 -1 (-1225 1675)(-1050 1675);
WIRE 16 -1 (-1050 1675)(-1050 1525);
WIRE 16 -1 (-1500 5200)(-1500 5225);
WIRE 16 -1 (-1125 5225)(-1125 5200);
WIRE 16 -1 (-700 5525)(-375 5525);
WIRE 16 -1 (-375 5525)(-375 5700);
WIRE 16 -1 (-8900 3850)(-8900 3950);
WIRE 16 -1 (-8900 5400)(-8900 5600);
WIRE 16 -1 (-8900 5100)(-8900 5000);
WIRE 16 -1 (-8900 6325)(-8900 6425);
WIRE 16 -1 (-8925 1900)(-8925 1750);
WIRE 16 -1 (-7900 4125)(-7900 4000);
WIRE 16 -1 (-6875 775)(-6875 675);
WIRE 16 -1 (-6525 775)(-6525 650);
WIRE 16 -1 (-4550 625)(-4550 550);
WIRE 16 -1 (-4300 625)(-4300 550);
WIRE 16 -1 (-7550 1675)(-7550 1550);
WIRE 16 -1 (-7200 1675)(-7200 1550);
WIRE 16 -1 (-7575 2975)(-7575 2850);
WIRE 16 -1 (-8925 2550)(-8925 2650);
WIRE 16 -1 (-7550 4125)(-7550 4000);
WIRE 16 -1 (-5000 3250)(-5000 3225);
WIRE 16 -1 (-4975 3775)(-4975 3725);
WIRE 16 -1 (-4975 4250)(-4975 4225);
WIRE 16 -1 (-4950 4775)(-4950 4725);
WIRE 16 -1 (-4650 2700)(-4450 2700);
WIRE 16 -1 (-4650 2700)(-4650 2900);
WIRE 16 -1 (-7825 5475)(-7825 5350);
WIRE 16 -1 (-7475 5475)(-7475 5350);
WIRE 16 2175 (-8000 1500)(-8000 675);
WIRE 16 2175 (-8500 1500)(-8000 1500);
WIRE 16 2175 (-8500 675)(-8000 675);
WIRE 16 2175 (-8500 1500)(-8500 675);
WIRE 16 -1 (-7325 1300)(-6525 1300);
FORCEPROP 0 LAST CDS_PHYS_NET_NAME P3V3_PDB_AUX_ADC_MAM
J 0
(-6760 1348);
PAINT MONO (-6760 1348);
DISPLAY INVISIBLE (-6760 1348);
FORCEPROP 2 LAST SIG_NAME P3V3_PDB_AUX_ADC_MAM
J 0
(-7085 1310);
DISPLAY 0.510638 (-7085 1310);
PAINT WHITE (-7085 1310);
WIRE 16 -1 (-6525 1300)(-6350 1300);
WIRE 16 -1 (-6525 975)(-6525 1300);
WIRE 16 -1 (-6875 1150)(-6350 1150);
FORCEPROP 0 LAST CDS_PHYS_NET_NAME P3V3_PDB_AUX_ADC_TIC
J 0
(-6485 1198);
PAINT MONO (-6485 1198);
DISPLAY INVISIBLE (-6485 1198);
WIRE 16 -1 (-6875 975)(-6875 1150);
WIRE 16 -1 (-7325 1150)(-6875 1150);
FORCEPROP 2 LAST SIG_NAME P3V3_PDB_AUX_ADC_TIC
J 0
(-7085 1160);
DISPLAY 0.510638 (-7085 1160);
PAINT WHITE (-7085 1160);
WIRE 16 2175 (-5900 3300)(-5375 3300);
WIRE 16 2175 (-5900 3650)(-5900 3300);
WIRE 16 2175 (-5375 3650)(-5375 3300);
WIRE 16 2175 (-5900 3650)(-5375 3650);
FORCEPROP 0 LAST M1 CO-LAYOUT
J 0
(-5850 3650);
DISPLAY 1.021277 (-5850 3650);
WIRE 16 -1 (-5600 3525)(-5225 3525);
FORCEPROP 2 LAST SIG_NAME P12V_E1S_0_ISENSE_TIC
J 0
(-5335 3535);
DISPLAY 0.510638 (-5335 3535);
PAINT WHITE (-5335 3535);
WIRE 16 -1 (-5225 3525)(-5000 3525);
FORCEPROP 0 LAST CDS_PHYS_NET_NAME P12V_E1S_0_ISENSE_TIC
J 0
(-5035 3573);
PAINT MONO (-5035 3573);
DISPLAY INVISIBLE (-5035 3573);
WIRE 16 -1 (-5225 3375)(-5225 3525);
WIRE 16 -1 (-5600 3375)(-5225 3375);
WIRE 16 -1 (-5000 3525)(-4775 3525);
WIRE 16 -1 (-5000 3450)(-5000 3525);
WIRE 16 2175 (-5900 4150)(-5375 4150);
FORCEPROP 0 LAST M1 CO-LAYOUT
J 0
(-5850 4150);
DISPLAY 1.021277 (-5850 4150);
WIRE 16 2175 (-5900 4150)(-5900 3800);
WIRE 16 2175 (-5375 4150)(-5375 3800);
WIRE 16 2175 (-5900 3800)(-5375 3800);
WIRE 16 -1 (-5600 4025)(-5225 4025);
FORCEPROP 2 LAST SIG_NAME P12V_E1S_0_ISENSE_MAM
J 0
(-5335 4035);
DISPLAY 0.510638 (-5335 4035);
PAINT WHITE (-5335 4035);
WIRE 16 -1 (-5225 4025)(-4975 4025);
FORCEPROP 0 LAST CDS_PHYS_NET_NAME P12V_E1S_0_ISENSE_MAM
J 0
(-5035 4073);
PAINT MONO (-5035 4073);
DISPLAY INVISIBLE (-5035 4073);
WIRE 16 -1 (-5225 3875)(-5225 4025);
WIRE 16 -1 (-5600 3875)(-5225 3875);
WIRE 16 -1 (-4775 4025)(-4975 4025);
WIRE 16 -1 (-4975 3975)(-4975 4025);
WIRE 16 -1 (-5200 4525)(-4975 4525);
FORCEPROP 0 LAST CDS_PHYS_NET_NAME P12V_OCP_V3_2_ISENSE_TIC
J 0
(-5010 4573);
PAINT MONO (-5010 4573);
DISPLAY INVISIBLE (-5010 4573);
WIRE 16 -1 (-5200 4375)(-5200 4525);
WIRE 16 -1 (-5575 4525)(-5200 4525);
FORCEPROP 2 LAST SIG_NAME P12V_OCP_V3_2_ISENSE_TIC
J 0
(-5310 4535);
DISPLAY 0.510638 (-5310 4535);
PAINT WHITE (-5310 4535);
WIRE 16 -1 (-4975 4525)(-4750 4525);
WIRE 16 -1 (-4975 4450)(-4975 4525);
WIRE 16 -1 (-5575 4375)(-5200 4375);
WIRE 16 -1 (-7575 3175)(-7575 3500);
WIRE 16 -1 (-7500 3500)(-7575 3500);
WIRE 16 -1 (-8175 3500)(-7575 3500);
FORCEPROP 0 LAST CDS_PHYS_NET_NAME P5V_ADC_MAM
J 0
(-7610 3548);
PAINT MONO (-7610 3548);
DISPLAY INVISIBLE (-7610 3548);
FORCEPROP 2 LAST SIG_NAME P5V_ADC_MAM
J 0
(-7935 3510);
DISPLAY 0.510638 (-7935 3510);
PAINT WHITE (-7935 3510);
WIRE 16 2175 (-5825 5625)(-5325 5625);
FORCEPROP 0 LAST M1 CO-LAYOUT
J 0
(-5775 5625);
DISPLAY 1.021277 (-5775 5625);
WIRE 16 2175 (-5825 5625)(-5825 5275);
WIRE 16 2175 (-5325 5625)(-5325 5275);
WIRE 16 2175 (-5825 5275)(-5325 5275);
WIRE 16 -1 (-5150 6525)(-5575 6525);
WIRE 16 -1 (-5150 6525)(-4775 6525);
WIRE 16 -1 (-5150 6400)(-5150 6525);
WIRE 16 -1 (-5575 6525)(-5575 6400);
WIRE 16 -1 (-5575 6525)(-6000 6525);
WIRE 16 -1 (-6000 6400)(-6000 6525);
WIRE 16 -1 (-6000 6525)(-6450 6525);
WIRE 16 -1 (-5150 6400)(-5575 6400);
WIRE 16 -1 (-5575 6400)(-5575 6275);
WIRE 16 -1 (-6000 6400)(-5575 6400);
WIRE 16 -1 (-4775 6400)(-5150 6400);
WIRE 16 -1 (-5150 6275)(-5150 6400);
WIRE 16 -1 (-4325 6525)(-4775 6525);
WIRE 16 -1 (-4775 6525)(-4775 6400);
WIRE 16 -1 (-4775 6400)(-4325 6400);
WIRE 16 -1 (-4775 6400)(-4775 6275);
WIRE 16 -1 (-4025 6525)(-4325 6525);
WIRE 16 -1 (-4325 6400)(-4325 6525);
WIRE 16 -1 (-5575 6275)(-5150 6275);
WIRE 16 -1 (-5150 6275)(-4775 6275);
WIRE 16 -1 (-6000 6275)(-6000 6400);
WIRE 16 -1 (-6450 6400)(-6000 6400);
WIRE 16 -1 (-6000 6275)(-5575 6275);
WIRE 16 -1 (-6450 6525)(-6450 6400);
WIRE 16 -1 (-6450 6400)(-6450 6275);
WIRE 16 -1 (-6450 6275)(-6000 6275);
WIRE 16 -1 (-4775 6275)(-4325 6275);
WIRE 16 -1 (-4325 6400)(-4025 6400);
WIRE 16 -1 (-4325 6275)(-4325 6400);
WIRE 16 -1 (-4025 6400)(-4025 6525);
WIRE 16 -1 (-4025 6275)(-4025 6400);
WIRE 16 -1 (-4325 6275)(-4025 6275);
WIRE 16 -1 (-5550 5850)(-5175 5850);
WIRE 16 -1 (-5175 5850)(-5175 6000);
WIRE 16 -1 (-5175 6000)(-4925 6000);
FORCEPROP 0 LAST CDS_PHYS_NET_NAME P12V_OCP_SFF_ISENSE_MAM
J 0
(-4985 6048);
PAINT MONO (-4985 6048);
DISPLAY INVISIBLE (-4985 6048);
WIRE 16 -1 (-5550 6000)(-5175 6000);
FORCEPROP 2 LAST SIG_NAME P12V_OCP_SFF_ISENSE_MAM
J 0
(-5285 6010);
DISPLAY 0.510638 (-5285 6010);
PAINT WHITE (-5285 6010);
WIRE 16 -1 (-4725 6000)(-4925 6000);
WIRE 16 -1 (-4925 5950)(-4925 6000);
WIRE 16 2175 (-5850 5150)(-5350 5150);
FORCEPROP 0 LAST M1 CO-LAYOUT
J 0
(-5800 5150);
DISPLAY 1.021277 (-5800 5150);
WIRE 16 2175 (-5850 5150)(-5850 4800);
WIRE 16 2175 (-5350 5150)(-5350 4800);
WIRE 16 2175 (-5850 4800)(-5350 4800);
WIRE 16 -1 (-6550 4525)(-5775 4525);
FORCEPROP 0 LAST CDS_PHYS_NET_NAME P12V_OCP_V3_2_ISENSE_MAM_TIC
J 0
(-5910 4573);
PAINT MONO (-5910 4573);
DISPLAY INVISIBLE (-5910 4573);
FORCEPROP 2 LAST SIG_NAME P12V_OCP_V3_2_ISENSE_MAM_TIC
J 0
(-6535 4535);
DISPLAY 0.510638 (-6535 4535);
PAINT WHITE (-6535 4535);
WIRE 16 -1 (-6550 4375)(-5775 4375);
FORCEPROP 0 LAST CDS_PHYS_NET_NAME P12V_OCP_V3_2_ISENSE_MPS_TIC
J 0
(-6010 4423);
PAINT MONO (-6010 4423);
DISPLAY INVISIBLE (-6010 4423);
FORCEPROP 2 LAST SIG_NAME P12V_OCP_V3_2_ISENSE_MPS_TIC
J 0
(-6535 4385);
DISPLAY 0.510638 (-6535 4385);
PAINT WHITE (-6535 4385);
WIRE 16 -1 (-6575 4025)(-5800 4025);
FORCEPROP 0 LAST CDS_PHYS_NET_NAME P12V_E1S_0_ISENSE_MAM_MAM
J 0
(-5935 4073);
PAINT MONO (-5935 4073);
DISPLAY INVISIBLE (-5935 4073);
FORCEPROP 2 LAST SIG_NAME P12V_E1S_0_ISENSE_MAM_MAM
J 0
(-6585 4035);
DISPLAY 0.510638 (-6585 4035);
PAINT WHITE (-6585 4035);
WIRE 16 -1 (-6575 3875)(-5800 3875);
FORCEPROP 0 LAST CDS_PHYS_NET_NAME P12V_E1S_0_ISENSE_MPS_MAM
J 0
(-6035 3923);
PAINT MONO (-6035 3923);
DISPLAY INVISIBLE (-6035 3923);
FORCEPROP 2 LAST SIG_NAME P12V_E1S_0_ISENSE_MPS_MAM
J 0
(-6585 3885);
DISPLAY 0.510638 (-6585 3885);
PAINT WHITE (-6585 3885);
WIRE 16 -1 (-6575 3525)(-5800 3525);
FORCEPROP 0 LAST CDS_PHYS_NET_NAME P12V_E1S_0_ISENSE_MAM_TIC
J 0
(-5935 3573);
PAINT MONO (-5935 3573);
DISPLAY INVISIBLE (-5935 3573);
FORCEPROP 2 LAST SIG_NAME P12V_E1S_0_ISENSE_MAM_TIC
J 0
(-6535 3535);
DISPLAY 0.510638 (-6535 3535);
PAINT WHITE (-6535 3535);
WIRE 16 2175 (-8450 3700)(-7950 3700);
FORCEPROP 0 LAST M1 CO-LAYOUT
J 0
(-8350 3725);
DISPLAY 1.021277 (-8350 3725);
WIRE 16 2175 (-8450 3700)(-8450 3225);
WIRE 16 2175 (-7950 3700)(-7950 3225);
WIRE 16 2175 (-8450 3225)(-7950 3225);
WIRE 16 -1 (-8900 3500)(-8500 3500);
FORCEPROP 0 LAST CDS_PHYS_NET_NAME P5V_ADC
J 0
(-8510 3548);
PAINT MONO (-8510 3548);
DISPLAY INVISIBLE (-8510 3548);
FORCEPROP 2 LAST SIG_NAME P5V_ADC
J 0
(-8710 3510);
DISPLAY 0.510638 (-8710 3510);
PAINT WHITE (-8710 3510);
FORCEPROP 2 LASTPROP $XRERR UNIQUE?
J 0
(-8950 3510);
DISPLAY 0.638298 (-8950 3510);
PAINT MONO (-8950 3510);
DISPLAY INVISIBLE (-8950 3510);
WIRE 16 -1 (-8900 3650)(-8900 3500);
WIRE 16 -1 (-8900 3500)(-8900 3300);
WIRE 16 -1 (-8500 3500)(-8375 3500);
WIRE 16 -1 (-8500 3500)(-8500 3350);
WIRE 16 -1 (-8375 3350)(-8500 3350);
WIRE 16 -1 (-6575 3375)(-5800 3375);
FORCEPROP 0 LAST CDS_PHYS_NET_NAME P12V_E1S_0_ISENSE_MPS_TIC
J 0
(-6035 3423);
PAINT MONO (-6035 3423);
DISPLAY INVISIBLE (-6035 3423);
FORCEPROP 2 LAST SIG_NAME P12V_E1S_0_ISENSE_MPS_TIC
J 0
(-6535 3385);
DISPLAY 0.510638 (-6535 3385);
PAINT WHITE (-6535 3385);
WIRE 16 -1 (-2025 2275)(-3475 2275);
FORCEPROP 0 LAST CDS_PHYS_NET_NAME ADC128_VREF
J 0
(-2335 2323);
PAINT MONO (-2335 2323);
DISPLAY INVISIBLE (-2335 2323);
FORCEPROP 2 LAST SIG_NAME ADC128_VREF
J 0
(-2685 2285);
DISPLAY 0.510638 (-2685 2285);
PAINT WHITE (-2685 2285);
FORCEPROP 2 LASTPROP $XRERR UNIQUE?
J 0
(-2925 2285);
DISPLAY 0.638298 (-2925 2285);
PAINT MONO (-2925 2285);
DISPLAY INVISIBLE (-2925 2285);
WIRE 16 -1 (-3475 2400)(-3475 2275);
WIRE 16 -1 (-3475 2275)(-3475 2100);
WIRE 16 -1 (-2025 2175)(-2700 2175);
FORCEPROP 0 LAST CDS_PHYS_NET_NAME ADC128_A1
J 0
(-2335 2223);
PAINT MONO (-2335 2223);
DISPLAY INVISIBLE (-2335 2223);
FORCEPROP 2 LAST SIG_NAME ADC128_A1
J 0
(-2685 2185);
DISPLAY 0.510638 (-2685 2185);
PAINT WHITE (-2685 2185);
WIRE 16 -1 (-2025 2125)(-2700 2125);
FORCEPROP 0 LAST CDS_PHYS_NET_NAME ADC128_A0
J 0
(-2335 2173);
PAINT MONO (-2335 2173);
DISPLAY INVISIBLE (-2335 2173);
FORCEPROP 2 LAST SIG_NAME ADC128_A0
J 0
(-2685 2135);
DISPLAY 0.510638 (-2685 2135);
PAINT WHITE (-2685 2135);
WIRE 16 -1 (-2025 2025)(-2700 2025);
FORCEPROP 0 LAST CDS_PHYS_NET_NAME P12V_E1S_0_ISENSE_TIC
J 0
(-2335 2073);
PAINT MONO (-2335 2073);
DISPLAY INVISIBLE (-2335 2073);
FORCEPROP 2 LAST SIG_NAME P12V_E1S_0_ISENSE_TIC
J 0
(-2685 2035);
DISPLAY 0.510638 (-2685 2035);
PAINT WHITE (-2685 2035);
WIRE 16 -1 (-5575 4875)(-5200 4875);
WIRE 16 -1 (-5200 4875)(-5200 5025);
WIRE 16 -1 (-5200 5025)(-4950 5025);
FORCEPROP 0 LAST CDS_PHYS_NET_NAME P12V_OCP_V3_2_ISENSE_MAM
J 0
(-5010 5073);
PAINT MONO (-5010 5073);
DISPLAY INVISIBLE (-5010 5073);
WIRE 16 -1 (-5575 5025)(-5200 5025);
FORCEPROP 2 LAST SIG_NAME P12V_OCP_V3_2_ISENSE_MAM
J 0
(-5310 5035);
DISPLAY 0.510638 (-5310 5035);
PAINT WHITE (-5310 5035);
WIRE 16 -1 (-4750 5025)(-4950 5025);
WIRE 16 -1 (-4950 4975)(-4950 5025);
WIRE 16 2175 (-5850 4650)(-5350 4650);
FORCEPROP 0 LAST M1 CO-LAYOUT
J 0
(-5800 4650);
DISPLAY 1.021277 (-5800 4650);
WIRE 16 2175 (-5850 4650)(-5850 4300);
WIRE 16 2175 (-5350 4650)(-5350 4300);
WIRE 16 2175 (-5850 4300)(-5350 4300);
WIRE 16 -1 (-6525 5850)(-5750 5850);
FORCEPROP 0 LAST CDS_PHYS_NET_NAME P12V_OCP_SFF_ISENSE_MPS_MAM
J 0
(-5885 5898);
PAINT MONO (-5885 5898);
DISPLAY INVISIBLE (-5885 5898);
FORCEPROP 2 LAST SIG_NAME P12V_OCP_SFF_ISENSE_MPS_MAM
J 0
(-6485 5860);
DISPLAY 0.510638 (-6485 5860);
PAINT WHITE (-6485 5860);
WIRE 16 -1 (-4950 5425)(-4950 5500);
WIRE 16 -1 (-4950 5500)(-4725 5500);
WIRE 16 -1 (-5175 5500)(-4950 5500);
FORCEPROP 0 LAST CDS_PHYS_NET_NAME P12V_OCP_SFF_ISENSE_TIC
J 0
(-4985 5548);
PAINT MONO (-4985 5548);
DISPLAY INVISIBLE (-4985 5548);
WIRE 16 -1 (-5175 5350)(-5175 5500);
WIRE 16 -1 (-5550 5500)(-5175 5500);
FORCEPROP 2 LAST SIG_NAME P12V_OCP_SFF_ISENSE_TIC
J 0
(-5285 5510);
DISPLAY 0.510638 (-5285 5510);
PAINT WHITE (-5285 5510);
WIRE 16 -1 (-5550 5350)(-5175 5350);
WIRE 16 -1 (-6525 5350)(-5750 5350);
FORCEPROP 0 LAST CDS_PHYS_NET_NAME P12V_OCP_SFF_ISENSE_MPS_TIC
J 0
(-5985 5398);
PAINT MONO (-5985 5398);
DISPLAY INVISIBLE (-5985 5398);
FORCEPROP 2 LAST SIG_NAME P12V_OCP_SFF_ISENSE_MPS_TIC
J 0
(-6485 5360);
DISPLAY 0.510638 (-6485 5360);
PAINT WHITE (-6485 5360);
WIRE 16 -1 (-2025 5250)(-1875 5250);
WIRE 16 -1 (-1875 5250)(-1875 5525);
WIRE 16 -1 (-1875 5525)(-1500 5525);
FORCEPROP 2 LAST SIG_NAME P3V3_MAX11617_VDD
J 0
(-1810 5535);
DISPLAY 0.510638 (-1810 5535);
PAINT WHITE (-1810 5535);
FORCEPROP 2 LASTPROP $XRERR UNIQUE?
J 0
(-2050 5535);
DISPLAY 0.638298 (-2050 5535);
PAINT MONO (-2050 5535);
DISPLAY INVISIBLE (-2050 5535);
WIRE 16 -1 (-1125 5525)(-1500 5525);
WIRE 16 -1 (-1500 5425)(-1500 5525);
WIRE 16 -1 (-900 5525)(-1125 5525);
WIRE 16 -1 (-1125 5425)(-1125 5525);
WIRE 16 -1 (-2925 5250)(-2925 5525);
WIRE 16 -1 (-2825 5250)(-2925 5250);
WIRE 16 -1 (-2925 5525)(-3375 5525);
FORCEPROP 2 LAST SIG_NAME MAX11617_VREF_R
J 0
(-3085 5535);
DISPLAY 0.638298 (-3085 5535);
PAINT WHITE (-3085 5535);
FORCEPROP 2 LASTPROP $XRERR UNIQUE?
J 0
(-3325 5535);
DISPLAY 0.638298 (-3325 5535);
PAINT MONO (-3325 5535);
DISPLAY INVISIBLE (-3325 5535);
WIRE 16 -1 (-4200 5450)(-4200 5525);
WIRE 16 -1 (-4200 5525)(-3825 5525);
FORCEPROP 2 LAST SIG_NAME MAX11617_VREF
J 0
(-4160 5535);
DISPLAY 0.638298 (-4160 5535);
PAINT WHITE (-4160 5535);
FORCEPROP 2 LASTPROP $XRERR UNIQUE?
J 0
(-4400 5535);
DISPLAY 0.638298 (-4400 5535);
PAINT MONO (-4400 5535);
DISPLAY INVISIBLE (-4400 5535);
WIRE 16 -1 (-3575 5525)(-3825 5525);
WIRE 16 -1 (-3825 5450)(-3825 5525);
WIRE 16 -1 (-2925 4950)(-2925 5050);
WIRE 16 -1 (-2825 4950)(-2925 4950);
WIRE 16 -1 (-2925 4300)(-2925 4950);
WIRE 16 -1 (-2925 5150)(-2925 5050);
WIRE 16 -1 (-2825 5050)(-2925 5050);
WIRE 16 -1 (-2825 5150)(-2925 5150);
WIRE 16 -1 (-1400 3650)(-2300 3650);
FORCEPROP 0 LAST CDS_PHYS_NET_NAME SMB_SEN_TIC_3V3AUX_SCL
J 0
(-1860 3698);
PAINT MONO (-1860 3698);
DISPLAY INVISIBLE (-1860 3698);
FORCEPROP 2 LAST SIG_NAME SMB_SEN_MAM_3V3AUX_SCL
J 0
(-1985 3660);
DISPLAY 0.510638 (-1985 3660);
PAINT WHITE (-1985 3660);
WIRE 16 -1 (-2025 5150)(-1900 5150);
WIRE 16 -1 (-1900 4350)(-1900 5150);
WIRE 16 -1 (-4550 1425)(-4550 1600);
WIRE 16 -1 (-4300 1600)(-4550 1600);
WIRE 16 -1 (-4550 1675)(-4550 1600);
WIRE 16 -1 (-4300 1425)(-4300 1600);
WIRE 16 -1 (-3850 2400)(-3850 2225);
WIRE 16 -1 (-4175 2225)(-3850 2225);
WIRE 16 -1 (-4175 2400)(-4175 2225);
WIRE 16 2175 (-5800 5775)(-5325 5775);
WIRE 16 2175 (-5800 6125)(-5800 5775);
WIRE 16 2175 (-5325 6125)(-5325 5775);
WIRE 16 2175 (-5800 6125)(-5325 6125);
FORCEPROP 0 LAST M1 CO-LAYOUT
J 0
(-5750 6125);
DISPLAY 1.021277 (-5750 6125);
WIRE 16 -1 (-6550 4875)(-5775 4875);
FORCEPROP 0 LAST CDS_PHYS_NET_NAME P12V_OCP_V3_2_ISENSE_MPS_MAM
J 0
(-6010 4923);
PAINT MONO (-6010 4923);
DISPLAY INVISIBLE (-6010 4923);
FORCEPROP 2 LAST SIG_NAME P12V_OCP_V3_2_ISENSE_MPS_MAM
J 0
(-6560 4885);
DISPLAY 0.510638 (-6560 4885);
PAINT WHITE (-6560 4885);
WIRE 16 -1 (-6525 6000)(-5750 6000);
FORCEPROP 0 LAST CDS_PHYS_NET_NAME P12V_OCP_SFF_ISENSE_MAM_MAM
J 0
(-5885 6048);
PAINT MONO (-5885 6048);
DISPLAY INVISIBLE (-5885 6048);
FORCEPROP 2 LAST SIG_NAME P12V_OCP_SFF_ISENSE_MAM_MAM
J 0
(-6485 6010);
DISPLAY 0.510638 (-6485 6010);
PAINT WHITE (-6485 6010);
WIRE 16 -1 (-7525 1150)(-7650 1150);
WIRE 16 -1 (-7650 1150)(-7650 1300);
WIRE 16 -1 (-7650 1300)(-7525 1300);
WIRE 16 -1 (-7825 1300)(-7650 1300);
FORCEPROP 0 LAST CDS_PHYS_NET_NAME P1V581_PDB_ADC
J 0
(-7810 1348);
PAINT MONO (-7810 1348);
DISPLAY INVISIBLE (-7810 1348);
WIRE 16 -1 (-7825 1300)(-7825 1125);
WIRE 16 -1 (-8375 1125)(-7825 1125);
FORCEPROP 2 LAST SIG_NAME P1V581_PDB_ADC
J 0
(-8160 1135);
DISPLAY 0.510638 (-8160 1135);
PAINT WHITE (-8160 1135);
FORCEPROP 2 LASTPROP $XRERR UNIQUE?
J 0
(-8400 1135);
DISPLAY 0.638298 (-8400 1135);
PAINT MONO (-8400 1135);
DISPLAY INVISIBLE (-8400 1135);
WIRE 16 -1 (-8375 1225)(-8375 1125);
WIRE 16 -1 (-8375 1125)(-8375 1050);
WIRE 16 2175 (-7675 1050)(-7100 1050);
WIRE 16 2175 (-7675 1400)(-7675 1050);
WIRE 16 2175 (-7100 1400)(-7100 1050);
WIRE 16 2175 (-7675 1400)(-7100 1400);
FORCEPROP 0 LAST M1 CO-LAYOUT
J 0
(-7575 1425);
DISPLAY 1.021277 (-7575 1425);
WIRE 16 -1 (-7200 1875)(-7200 2200);
WIRE 16 -1 (-7200 2200)(-7025 2200);
WIRE 16 -1 (-8000 2200)(-7200 2200);
FORCEPROP 0 LAST CDS_PHYS_NET_NAME P12V_AUX_ADC_MAM
J 0
(-7435 2248);
PAINT MONO (-7435 2248);
DISPLAY INVISIBLE (-7435 2248);
FORCEPROP 2 LAST SIG_NAME P12V_AUX_ADC_MAM
J 0
(-7760 2210);
DISPLAY 0.510638 (-7760 2210);
PAINT WHITE (-7760 2210);
WIRE 16 -1 (-8375 1550)(-8375 1425);
WIRE 16 -1 (-9000 1550)(-8375 1550);
FORCEPROP 2 LAST SIG_NAME P3V3_PDB_AUX_ADC
J 0
(-8960 1560);
DISPLAY 0.510638 (-8960 1560);
PAINT WHITE (-8960 1560);
WIRE 16 2175 (-8375 1925)(-7775 1925);
WIRE 16 2175 (-8375 2450)(-8375 1925);
WIRE 16 2175 (-7775 2450)(-7775 1925);
WIRE 16 2175 (-8375 2450)(-7775 2450);
FORCEPROP 0 LAST M1 CO-LAYOUT
J 0
(-8275 2475);
DISPLAY 1.021277 (-8275 2475);
WIRE 16 -1 (-7550 1875)(-7550 2050);
WIRE 16 -1 (-7550 2050)(-7025 2050);
FORCEPROP 0 LAST CDS_PHYS_NET_NAME P12V_AUX_ADC_TIC
J 0
(-7160 2098);
PAINT MONO (-7160 2098);
DISPLAY INVISIBLE (-7160 2098);
WIRE 16 -1 (-8000 2050)(-7550 2050);
FORCEPROP 2 LAST SIG_NAME P12V_AUX_ADC_TIC
J 0
(-7760 2060);
DISPLAY 0.510638 (-7760 2060);
PAINT WHITE (-7760 2060);
WIRE 16 -1 (-8200 2050)(-8500 2050);
WIRE 16 -1 (-8500 2050)(-8500 2200);
WIRE 16 -1 (-8500 2200)(-8200 2200);
FORCEPROP 0 LAST CDS_PHYS_NET_NAME P12V_AUX_ADC
J 0
(-8385 2248);
PAINT MONO (-8385 2248);
DISPLAY INVISIBLE (-8385 2248);
WIRE 16 -1 (-8925 2200)(-8500 2200);
FORCEPROP 2 LAST SIG_NAME P12V_AUX_ADC
J 0
(-8860 2210);
DISPLAY 0.510638 (-8860 2210);
PAINT WHITE (-8860 2210);
FORCEPROP 2 LASTPROP $XRERR UNIQUE?
J 0
(-9100 2210);
DISPLAY 0.638298 (-9100 2210);
PAINT MONO (-9100 2210);
DISPLAY INVISIBLE (-9100 2210);
WIRE 16 -1 (-8925 2350)(-8925 2200);
WIRE 16 -1 (-8925 2100)(-8925 2200);
WIRE 16 -1 (-8175 3350)(-7925 3350);
FORCEPROP 2 LAST SIG_NAME P5V_ADC_TIC
J 0
(-7935 3360);
DISPLAY 0.510638 (-7935 3360);
PAINT WHITE (-7935 3360);
WIRE 16 -1 (-7500 3350)(-7925 3350);
FORCEPROP 0 LAST CDS_PHYS_NET_NAME P5V_ADC_TIC
J 0
(-7635 3398);
PAINT MONO (-7635 3398);
DISPLAY INVISIBLE (-7635 3398);
WIRE 16 -1 (-7925 3175)(-7925 3350);
WIRE 16 -1 (-7550 4325)(-7550 4650);
WIRE 16 -1 (-7500 4650)(-7550 4650);
WIRE 16 -1 (-8175 4650)(-7550 4650);
FORCEPROP 0 LAST CDS_PHYS_NET_NAME P3V3_ADC_MAM
J 0
(-7610 4698);
PAINT MONO (-7610 4698);
DISPLAY INVISIBLE (-7610 4698);
FORCEPROP 2 LAST SIG_NAME P3V3_ADC_MAM
J 0
(-7935 4660);
DISPLAY 0.510638 (-7935 4660);
PAINT WHITE (-7935 4660);
WIRE 16 -1 (-8175 4500)(-7900 4500);
FORCEPROP 2 LAST SIG_NAME P3V3_ADC_TIC
J 0
(-7935 4510);
DISPLAY 0.510638 (-7935 4510);
PAINT WHITE (-7935 4510);
WIRE 16 -1 (-7500 4500)(-7900 4500);
FORCEPROP 0 LAST CDS_PHYS_NET_NAME P3V3_ADC_TIC
J 0
(-7635 4548);
PAINT MONO (-7635 4548);
DISPLAY INVISIBLE (-7635 4548);
WIRE 16 -1 (-7900 4325)(-7900 4500);
WIRE 16 2175 (-8550 4375)(-7950 4375);
WIRE 16 2175 (-8550 4875)(-8550 4375);
WIRE 16 2175 (-7950 4875)(-7950 4375);
WIRE 16 2175 (-8550 4875)(-7950 4875);
FORCEPROP 0 LAST M1 CO-LAYOUT
J 0
(-8450 4900);
DISPLAY 1.021277 (-8450 4900);
WIRE 16 -1 (-8100 5825)(-7825 5825);
FORCEPROP 2 LAST SIG_NAME P3V3_AUX_ADC_TIC
J 0
(-7860 5835);
DISPLAY 0.510638 (-7860 5835);
PAINT WHITE (-7860 5835);
WIRE 16 -1 (-7450 5825)(-7825 5825);
FORCEPROP 0 LAST CDS_PHYS_NET_NAME P3V3_AUX_ADC_TIC
J 0
(-7585 5873);
PAINT MONO (-7585 5873);
DISPLAY INVISIBLE (-7585 5873);
WIRE 16 -1 (-7825 5675)(-7825 5825);
WIRE 16 2175 (-8475 5700)(-7875 5700);
WIRE 16 2175 (-8475 6125)(-8475 5700);
WIRE 16 2175 (-7875 6125)(-7875 5700);
WIRE 16 2175 (-8475 6125)(-7875 6125);
FORCEPROP 0 LAST M1 CO-LAYOUT
J 0
(-8400 6200);
DISPLAY 1.021277 (-8400 6200);
WIRE 16 -1 (-7475 5675)(-7475 5975);
WIRE 16 -1 (-7450 5975)(-7475 5975);
WIRE 16 -1 (-8100 5975)(-7475 5975);
FORCEPROP 0 LAST CDS_PHYS_NET_NAME P3V3_AUX_ADC_MAM
J 0
(-7535 6023);
PAINT MONO (-7535 6023);
DISPLAY INVISIBLE (-7535 6023);
FORCEPROP 2 LAST SIG_NAME P3V3_AUX_ADC_MAM
J 0
(-7860 5985);
DISPLAY 0.510638 (-7860 5985);
PAINT WHITE (-7860 5985);
WIRE 16 -1 (-8375 4500)(-8475 4500);
WIRE 16 -1 (-8475 4650)(-8475 4500);
WIRE 16 -1 (-8475 4650)(-8375 4650);
FORCEPROP 0 LAST CDS_PHYS_NET_NAME P3V3_ADC
J 0
(-8360 4698);
PAINT MONO (-8360 4698);
DISPLAY INVISIBLE (-8360 4698);
WIRE 16 -1 (-8475 4650)(-8900 4650);
FORCEPROP 2 LAST SIG_NAME P3V3_ADC
J 0
(-8810 4660);
DISPLAY 0.510638 (-8810 4660);
PAINT WHITE (-8810 4660);
FORCEPROP 2 LASTPROP $XRERR UNIQUE?
J 0
(-9050 4660);
DISPLAY 0.638298 (-9050 4660);
PAINT MONO (-9050 4660);
DISPLAY INVISIBLE (-9050 4660);
WIRE 16 -1 (-8900 4800)(-8900 4650);
WIRE 16 -1 (-8900 4650)(-8900 4525);
WIRE 16 -1 (-8425 5975)(-8300 5975);
WIRE 16 -1 (-8425 5975)(-8425 5825);
WIRE 16 -1 (-8425 5975)(-8900 5975);
FORCEPROP 0 LAST CDS_PHYS_NET_NAME P3V3_AUX_ADC
J 0
(-8435 6023);
PAINT MONO (-8435 6023);
DISPLAY INVISIBLE (-8435 6023);
FORCEPROP 2 LAST SIG_NAME P3V3_AUX_ADC
J 0
(-8785 5985);
DISPLAY 0.510638 (-8785 5985);
PAINT WHITE (-8785 5985);
FORCEPROP 2 LASTPROP $XRERR UNIQUE?
J 0
(-9025 5985);
DISPLAY 0.638298 (-9025 5985);
PAINT MONO (-9025 5985);
DISPLAY INVISIBLE (-9025 5985);
WIRE 16 -1 (-8900 6125)(-8900 5975);
WIRE 16 -1 (-8900 5800)(-8900 5975);
WIRE 16 -1 (-8425 5825)(-8300 5825);
WIRE 16 -1 (-1225 4650)(-2025 4650);
FORCEPROP 0 LAST CDS_PHYS_NET_NAME P3V3_AUX_ADC_MAM
J 0
(-1535 4698);
PAINT MONO (-1535 4698);
DISPLAY INVISIBLE (-1535 4698);
FORCEPROP 2 LAST SIG_NAME P3V3_AUX_ADC_MAM
J 0
(-1760 4660);
DISPLAY 0.510638 (-1760 4660);
PAINT WHITE (-1760 4660);
WIRE 16 -1 (-1225 4550)(-2025 4550);
FORCEPROP 0 LAST CDS_PHYS_NET_NAME P3V3_ADC_MAM
J 0
(-1535 4598);
PAINT MONO (-1535 4598);
DISPLAY INVISIBLE (-1535 4598);
FORCEPROP 2 LAST SIG_NAME P3V3_ADC_MAM
J 0
(-1760 4560);
DISPLAY 0.510638 (-1760 4560);
PAINT WHITE (-1760 4560);
WIRE 16 -1 (-1200 4850)(-2025 4850);
FORCEPROP 0 LAST CDS_PHYS_NET_NAME P12V_E1S_0_ISENSE_MAM
J 0
(-1510 4898);
PAINT MONO (-1510 4898);
DISPLAY INVISIBLE (-1510 4898);
FORCEPROP 2 LAST SIG_NAME P12V_E1S_0_ISENSE_MAM
J 0
(-1760 4860);
DISPLAY 0.510638 (-1760 4860);
PAINT WHITE (-1760 4860);
WIRE 16 -1 (-1100 4950)(-2025 4950);
FORCEPROP 0 LAST CDS_PHYS_NET_NAME SMB_SEN_TIC_3V3AUX_SCL
J 0
(-1410 4998);
PAINT MONO (-1410 4998);
DISPLAY INVISIBLE (-1410 4998);
FORCEPROP 2 LAST SIG_NAME SMB_SEN_MAM_3V3AUX_SCL
J 0
(-1760 4960);
DISPLAY 0.510638 (-1760 4960);
PAINT WHITE (-1760 4960);
WIRE 16 -1 (-1100 5050)(-2025 5050);
FORCEPROP 0 LAST CDS_PHYS_NET_NAME SMB_SEN_TIC_3V3AUX_SDA
J 0
(-1410 5098);
PAINT MONO (-1410 5098);
DISPLAY INVISIBLE (-1410 5098);
FORCEPROP 2 LAST SIG_NAME SMB_SEN_MAM_3V3AUX_SDA
J 0
(-1760 5060);
DISPLAY 0.510638 (-1760 5060);
PAINT WHITE (-1760 5060);
WIRE 16 -1 (-1400 3700)(-2300 3700);
FORCEPROP 0 LAST CDS_PHYS_NET_NAME SMB_SEN_TIC_3V3AUX_SDA
J 0
(-1860 3748);
PAINT MONO (-1860 3748);
DISPLAY INVISIBLE (-1860 3748);
FORCEPROP 2 LAST SIG_NAME SMB_SEN_MAM_3V3AUX_SDA
J 0
(-1985 3710);
DISPLAY 0.510638 (-1985 3710);
PAINT WHITE (-1985 3710);
WIRE 16 -1 (-3350 3700)(-2500 3700);
FORCEPROP 0 LAST CDS_PHYS_NET_NAME SMB_VR_3V3AUX_SDA_R1
J 0
(-3310 3748);
PAINT MONO (-3310 3748);
DISPLAY INVISIBLE (-3310 3748);
FORCEPROP 2 LAST SIG_NAME SMB_SCM_2_R4_SDA
J 0
(-3250 3710);
DISPLAY 0.510638 (-3250 3710);
PAINT WHITE (-3250 3710);
WIRE 16 -1 (-3350 3650)(-2500 3650);
FORCEPROP 0 LAST CDS_PHYS_NET_NAME SMB_VR_3V3AUX_SCL_R1
J 0
(-3310 3698);
PAINT MONO (-3310 3698);
DISPLAY INVISIBLE (-3310 3698);
FORCEPROP 2 LAST SIG_NAME SMB_SCM_2_R4_SCL
J 0
(-3250 3660);
DISPLAY 0.510638 (-3250 3660);
PAINT WHITE (-3250 3660);
WIRE 16 -1 (-2825 4550)(-3625 4550);
FORCEPROP 0 LAST CDS_PHYS_NET_NAME P5V_ADC_MAM
J 0
(-3135 4598);
PAINT MONO (-3135 4598);
DISPLAY INVISIBLE (-3135 4598);
FORCEPROP 2 LAST SIG_NAME P5V_ADC_MAM
J 0
(-3535 4560);
DISPLAY 0.510638 (-3535 4560);
PAINT WHITE (-3535 4560);
WIRE 16 -1 (-2825 4750)(-3625 4750);
FORCEPROP 0 LAST CDS_PHYS_NET_NAME P12V_OCP_SFF_ISENSE_MAM
J 0
(-3135 4798);
PAINT MONO (-3135 4798);
DISPLAY INVISIBLE (-3135 4798);
FORCEPROP 2 LAST SIG_NAME P12V_OCP_SFF_ISENSE_MAM
J 0
(-3535 4760);
DISPLAY 0.510638 (-3535 4760);
PAINT WHITE (-3535 4760);
WIRE 16 -1 (-2825 4850)(-3625 4850);
FORCEPROP 0 LAST CDS_PHYS_NET_NAME P12V_AUX_ADC_MAM
J 0
(-3135 4898);
PAINT MONO (-3135 4898);
DISPLAY INVISIBLE (-3135 4898);
FORCEPROP 2 LAST SIG_NAME P12V_AUX_ADC_MAM
J 0
(-3535 4860);
DISPLAY 0.510638 (-3535 4860);
PAINT WHITE (-3535 4860);
WIRE 16 -1 (-2825 4650)(-3625 4650);
FORCEPROP 0 LAST CDS_PHYS_NET_NAME P12V_OCP_V3_2_ISENSE_MAM
J 0
(-3135 4698);
PAINT MONO (-3135 4698);
DISPLAY INVISIBLE (-3135 4698);
FORCEPROP 2 LAST SIG_NAME P12V_OCP_V3_2_ISENSE_MAM
J 0
(-3535 4660);
DISPLAY 0.510638 (-3535 4660);
PAINT WHITE (-3535 4660);
WIRE 16 -1 (-2250 2525)(-2025 2525);
WIRE 16 -1 (-2250 2700)(-2250 2525);
WIRE 16 -1 (-3475 2700)(-2250 2700);
WIRE 16 -1 (-3475 2700)(-3475 2600);
WIRE 16 -1 (-3850 2700)(-3475 2700);
WIRE 16 -1 (-3850 2700)(-3850 2600);
WIRE 16 -1 (-4175 2700)(-3850 2700);
WIRE 16 -1 (-4175 2700)(-4175 2600);
WIRE 16 -1 (-4250 2700)(-4175 2700);
FORCEPROP 2 LAST SIG_NAME P3V3_ADC128_VCC
J 0
(-4160 2710);
DISPLAY 0.510638 (-4160 2710);
PAINT WHITE (-4160 2710);
FORCEPROP 2 LASTPROP $XRERR UNIQUE?
J 0
(-4400 2710);
DISPLAY 0.638298 (-4400 2710);
PAINT MONO (-4400 2710);
DISPLAY INVISIBLE (-4400 2710);
WIRE 16 -1 (-2025 1675)(-2700 1675);
FORCEPROP 0 LAST CDS_PHYS_NET_NAME P12V_AUX_ADC_TIC
J 0
(-2335 1723);
PAINT MONO (-2335 1723);
DISPLAY INVISIBLE (-2335 1723);
FORCEPROP 2 LAST SIG_NAME P12V_AUX_ADC_TIC
J 0
(-2685 1685);
DISPLAY 0.510638 (-2685 1685);
PAINT WHITE (-2685 1685);
WIRE 16 -1 (-2025 1725)(-2700 1725);
FORCEPROP 0 LAST CDS_PHYS_NET_NAME P12V_OCP_SFF_ISENSE_TIC
J 0
(-2335 1773);
PAINT MONO (-2335 1773);
DISPLAY INVISIBLE (-2335 1773);
FORCEPROP 2 LAST SIG_NAME P12V_OCP_SFF_ISENSE_TIC
J 0
(-2685 1735);
DISPLAY 0.510638 (-2685 1735);
PAINT WHITE (-2685 1735);
WIRE 16 -1 (-2025 2425)(-2700 2425);
FORCEPROP 0 LAST CDS_PHYS_NET_NAME SMB_SEN_TIC_3V3AUX_SCL
J 0
(-2335 2473);
PAINT MONO (-2335 2473);
DISPLAY INVISIBLE (-2335 2473);
FORCEPROP 2 LAST SIG_NAME SMB_SEN_TIC_3V3AUX_SCL
J 0
(-2685 2435);
DISPLAY 0.510638 (-2685 2435);
PAINT WHITE (-2685 2435);
WIRE 16 -1 (-2025 1775)(-2700 1775);
FORCEPROP 0 LAST CDS_PHYS_NET_NAME P12V_OCP_V3_2_ISENSE_TIC
J 0
(-2335 1823);
PAINT MONO (-2335 1823);
DISPLAY INVISIBLE (-2335 1823);
FORCEPROP 2 LAST SIG_NAME P12V_OCP_V3_2_ISENSE_TIC
J 0
(-2685 1785);
DISPLAY 0.510638 (-2685 1785);
PAINT WHITE (-2685 1785);
WIRE 16 -1 (-2025 1875)(-2700 1875);
FORCEPROP 0 LAST CDS_PHYS_NET_NAME P3V3_ADC_TIC
J 0
(-2335 1923);
PAINT MONO (-2335 1923);
DISPLAY INVISIBLE (-2335 1923);
FORCEPROP 2 LAST SIG_NAME P3V3_ADC_TIC
J 0
(-2685 1885);
DISPLAY 0.510638 (-2685 1885);
PAINT WHITE (-2685 1885);
WIRE 16 -1 (-2025 1925)(-2700 1925);
FORCEPROP 0 LAST CDS_PHYS_NET_NAME P3V3_AUX_ADC_TIC
J 0
(-2335 1973);
PAINT MONO (-2335 1973);
DISPLAY INVISIBLE (-2335 1973);
FORCEPROP 2 LAST SIG_NAME P3V3_AUX_ADC_TIC
J 0
(-2685 1935);
DISPLAY 0.510638 (-2685 1935);
PAINT WHITE (-2685 1935);
WIRE 16 -1 (-2025 1975)(-2700 1975);
FORCEPROP 0 LAST CDS_PHYS_NET_NAME P3V3_PDB_AUX_ADC_TIC
J 0
(-2335 2023);
PAINT MONO (-2335 2023);
DISPLAY INVISIBLE (-2335 2023);
FORCEPROP 2 LAST SIG_NAME P3V3_PDB_AUX_ADC_TIC
J 0
(-2685 1985);
DISPLAY 0.510638 (-2685 1985);
PAINT WHITE (-2685 1985);
WIRE 16 -1 (-2025 2375)(-2700 2375);
FORCEPROP 0 LAST CDS_PHYS_NET_NAME SMB_SEN_TIC_3V3AUX_SDA
J 0
(-2335 2423);
PAINT MONO (-2335 2423);
DISPLAY INVISIBLE (-2335 2423);
FORCEPROP 2 LAST SIG_NAME SMB_SEN_TIC_3V3AUX_SDA
J 0
(-2685 2385);
DISPLAY 0.510638 (-2685 2385);
PAINT WHITE (-2685 2385);
WIRE 16 -1 (-6525 5500)(-5750 5500);
FORCEPROP 0 LAST CDS_PHYS_NET_NAME P12V_OCP_SFF_ISENSE_MAM_TIC
J 0
(-5885 5548);
PAINT MONO (-5885 5548);
DISPLAY INVISIBLE (-5885 5548);
FORCEPROP 2 LAST SIG_NAME P12V_OCP_SFF_ISENSE_MAM_TIC
J 0
(-6485 5510);
DISPLAY 0.510638 (-6485 5510);
PAINT WHITE (-6485 5510);
WIRE 16 -1 (-4300 1075)(-3475 1075);
FORCEPROP 0 LAST CDS_PHYS_NET_NAME ADC128_A0
J 0
(-3860 1117);
PAINT MONO (-3860 1117);
DISPLAY INVISIBLE (-3860 1117);
FORCEPROP 2 LAST SIG_NAME ADC128_A0
J 0
(-4085 1085);
DISPLAY 0.553191 (-4085 1085);
PAINT WHITE (-4085 1085);
WIRE 16 -1 (-4300 1225)(-4300 1075);
WIRE 16 -1 (-4300 1075)(-4300 825);
WIRE 16 -1 (-3475 975)(-4550 975);
FORCEPROP 0 LAST CDS_PHYS_NET_NAME ADC128_A1
J 0
(-3860 1017);
PAINT MONO (-3860 1017);
DISPLAY INVISIBLE (-3860 1017);
FORCEPROP 2 LAST SIG_NAME ADC128_A1
J 0
(-4085 985);
DISPLAY 0.553191 (-4085 985);
PAINT WHITE (-4085 985);
WIRE 16 -1 (-4550 1225)(-4550 975);
WIRE 16 -1 (-4550 975)(-4550 825);
WIRE 16 -1 (-2500 1050)(-1650 1050);
FORCEPROP 0 LAST CDS_PHYS_NET_NAME SMB_VR_3V3AUX_SDA_R1
J 0
(-2460 1098);
PAINT MONO (-2460 1098);
DISPLAY INVISIBLE (-2460 1098);
FORCEPROP 2 LAST SIG_NAME SMB_SCM_2_R4_SDA
J 0
(-2410 1060);
DISPLAY 0.510638 (-2410 1060);
PAINT WHITE (-2410 1060);
WIRE 16 -1 (-550 1050)(-1450 1050);
FORCEPROP 0 LAST CDS_PHYS_NET_NAME SMB_SEN_TIC_3V3AUX_SDA
J 0
(-1010 1098);
PAINT MONO (-1010 1098);
DISPLAY INVISIBLE (-1010 1098);
FORCEPROP 2 LAST SIG_NAME SMB_SEN_TIC_3V3AUX_SDA
J 0
(-1135 1060);
DISPLAY 0.510638 (-1135 1060);
PAINT WHITE (-1135 1060);
WIRE 16 -1 (-2500 1000)(-1650 1000);
FORCEPROP 0 LAST CDS_PHYS_NET_NAME SMB_VR_3V3AUX_SCL_R1
J 0
(-2460 1048);
PAINT MONO (-2460 1048);
DISPLAY INVISIBLE (-2460 1048);
FORCEPROP 2 LAST SIG_NAME SMB_SCM_2_R4_SCL
J 0
(-2410 1010);
DISPLAY 0.510638 (-2410 1010);
PAINT WHITE (-2410 1010);
WIRE 16 -1 (-550 1000)(-1450 1000);
FORCEPROP 0 LAST CDS_PHYS_NET_NAME SMB_SEN_TIC_3V3AUX_SCL
J 0
(-1010 1048);
PAINT MONO (-1010 1048);
DISPLAY INVISIBLE (-1010 1048);
FORCEPROP 2 LAST SIG_NAME SMB_SEN_TIC_3V3AUX_SCL
J 0
(-1135 1010);
DISPLAY 0.510638 (-1135 1010);
PAINT WHITE (-1135 1010);
WIRE 16 -1 (-2025 1825)(-2700 1825);
FORCEPROP 0 LAST CDS_PHYS_NET_NAME P5V_ADC_TIC
J 0
(-2335 1873);
PAINT MONO (-2335 1873);
DISPLAY INVISIBLE (-2335 1873);
FORCEPROP 2 LAST SIG_NAME P5V_ADC_TIC
J 0
(-2685 1835);
DISPLAY 0.510638 (-2685 1835);
PAINT WHITE (-2685 1835);
WIRE 16 -1 (-550 2525)(-1225 2525);
FORCEPROP 0 LAST CDS_PHYS_NET_NAME TP_ADC128_INT
J 0
(-860 2573);
PAINT MONO (-860 2573);
DISPLAY INVISIBLE (-860 2573);
FORCEPROP 2 LAST SIG_NAME TP_ADC128_INT
J 0
(-1160 2535);
DISPLAY 0.510638 (-1160 2535);
PAINT WHITE (-1160 2535);
FORCEPROP 2 LASTPROP $XRERR UNIQUE?
J 0
(-520 2525);
DISPLAY 0.638298 (-520 2525);
PAINT MONO (-520 2525);
DISPLAY INVISIBLE (-520 2525);
WIRE 16 -1 (-6550 5025)(-5775 5025);
FORCEPROP 0 LAST CDS_PHYS_NET_NAME P12V_OCP_V3_2_ISENSE_MAM_MAM
J 0
(-5910 5073);
PAINT MONO (-5910 5073);
DISPLAY INVISIBLE (-5910 5073);
FORCEPROP 2 LAST SIG_NAME P12V_OCP_V3_2_ISENSE_MAM_MAM
J 0
(-6560 5035);
DISPLAY 0.510638 (-6560 5035);
PAINT WHITE (-6560 5035);
WIRE 16 -1 (-1200 4750)(-2025 4750);
FORCEPROP 0 LAST CDS_PHYS_NET_NAME P3V3_PDB_AUX_ADC_MAM
J 0
(-1510 4798);
PAINT MONO (-1510 4798);
DISPLAY INVISIBLE (-1510 4798);
FORCEPROP 2 LAST SIG_NAME P3V3_PDB_AUX_ADC_MAM
J 0
(-1760 4760);
DISPLAY 0.510638 (-1760 4760);
PAINT WHITE (-1760 4760);
DOT 1 (-5200 5025);
DOT 1 (-4975 4025);
DOT 1 (-5575 6275);
DOT 1 (-4950 5025);
DOT 1 (-3825 5525);
DOT 1 (-1125 5525);
DOT 1 (-5200 4525);
DOT 1 (-5175 5500);
DOT 1 (-8375 1125);
DOT 1 (-8475 4650);
DOT 1 (-3475 2275);
DOT 1 (-4550 975);
DOT 1 (-4300 1075);
DOT 1 (-2925 4950);
DOT 1 (-2925 5050);
DOT 1 (-8925 2200);
DOT 1 (-8900 3500);
DOT 1 (-8500 3500);
DOT 1 (-8900 4650);
DOT 1 (-7900 4500);
DOT 1 (-8900 5975);
DOT 1 (-7650 1300);
DOT 1 (-7550 2050);
DOT 1 (-6875 1150);
DOT 1 (-6525 1300);
DOT 1 (-7575 3500);
DOT 1 (-7550 4650);
DOT 1 (-3850 2700);
DOT 1 (-5225 4025);
DOT 1 (-7825 5825);
DOT 1 (-6450 6400);
DOT 1 (-6000 6275);
DOT 1 (-6000 6400);
DOT 1 (-6000 6525);
DOT 1 (-5575 6400);
DOT 1 (-5575 6525);
DOT 1 (-5175 6000);
DOT 1 (-5150 6275);
DOT 1 (-5150 6400);
DOT 1 (-4925 6000);
DOT 1 (-5150 6525);
DOT 1 (-4775 6400);
DOT 1 (-4775 6275);
DOT 1 (-4325 6275);
DOT 1 (-4325 6400);
DOT 1 (-4775 6525);
DOT 1 (-4325 6525);
DOT 1 (-4025 6400);
DOT 1 (-1500 5525);
DOT 1 (-4550 1600);
DOT 1 (-5000 3525);
DOT 1 (-4975 4525);
DOT 1 (-7925 3350);
DOT 1 (-3475 2700);
DOT 1 (-4175 2700);
DOT 1 (-7475 5975);
DOT 1 (-8425 5975);
DOT 1 (-8500 2200);
DOT 1 (-7200 2200);
DOT 1 (-5225 3525);
DOT 1 (-4950 5500);
FORCENOTE
NOTE:R4567 NEED CHANGE TO 5.11K OHM ON EVT STATES AND POP R4568
(-9050 500) 0;
DISPLAY LEFT (-9050 500);
DISPLAY 1.021277 (-9050 500);
PAINT WHITE (-9050 500);
FORCENOTE
ADDR: 0X6A(8-BIT) / 0X35(7-BIT)
(-3675 4025) 0;
DISPLAY LEFT (-3675 4025);
DISPLAY 1.595745 (-3675 4025);
PAINT WHITE (-3675 4025);
FORCENOTE
V SOURCE P3V3_AUX   P3V3     P5V   P12V_AUX
(-6400 6425) 0;
DISPLAY LEFT (-6400 6425);
DISPLAY 1.021277 (-6400 6425);
PAINT WHITE (-6400 6425);
FORCENOTE
 VIN     1.599V   1.599V  1.677V   1.581V
(-6350 6300) 0;
DISPLAY LEFT (-6350 6300);
DISPLAY 1.021277 (-6350 6300);
PAINT WHITE (-6350 6300);
FORCENOTE
IF USE AD128,POP R3668,R3670
(-3975 825) 0;
DISPLAY LEFT (-3975 825);
DISPLAY 0.808511 (-3975 825);
PAINT WHITE (-3975 825);
FORCENOTE
ADDR: 0X3A(8-BIT) / 0X1D(7-BIT)
(-3125 1275) 0;
DISPLAY LEFT (-3125 1275);
DISPLAY 1.595745 (-3125 1275);
PAINT WHITE (-3125 1275);
FORCENOTE
VI=1.581V
(-9025 1100) 0;
DISPLAY LEFT (-9025 1100);
DISPLAY 1.021277 (-9025 1100);
PAINT WHITE (-9025 1100);
QUIT
